FILE_TYPE = MACRO_DRAWING;
SET COLOR_WIRE YELLOW;
SET COLOR_PROP ORANGE;
SET COLOR_DOT WHITE;
SET COLOR_ARC YELLOW;
SET COLOR_BODY GREEN;
SET COLOR_NOTE PURPLE;
SET PROP_DISPLAY VALUE;
SET PAGE_NUMBER P41;
FORCEADD GENOA_SP5..5
(-4700 3600);
FORCEPROP 1 LAST LOCATION U26
J 0
(-5345 6431);
DISPLAY 0.489362 (-5345 6431);
PAINT SKYBLUE (-5345 6431);
FORCEPROP 0 LAST $SEC 5
J 0
(-5325 6475);
DISPLAY 0.680851 (-5325 6475);
PAINT MONO (-5325 6475);
DISPLAY INVISIBLE (-5325 6475);
FORCEPROP 0 LAST CDS_SEC 5
J 0
(-5350 6425);
DISPLAY 1.021277 (-5350 6425);
DISPLAY INVISIBLE (-5350 6425);
FORCEPROP 0 LASTPIN (-5500 2975) $PN BC71
J 2
(-5510 2985);
DISPLAY 0.489362 (-5510 2985);
PAINT MONO (-5510 2985);
FORCEPROP 0 LASTPIN (-5500 2925) $PN BD70
J 2
(-5510 2935);
DISPLAY 0.489362 (-5510 2935);
PAINT MONO (-5510 2935);
FORCEPROP 0 LASTPIN (-5500 1825) $PN BF70
J 2
(-5510 1835);
DISPLAY 0.489362 (-5510 1835);
PAINT MONO (-5510 1835);
FORCEPROP 0 LASTPIN (-5500 1775) $PN BG71
J 2
(-5510 1785);
DISPLAY 0.489362 (-5510 1785);
PAINT MONO (-5510 1785);
FORCEPROP 0 LASTPIN (-5500 2125) $PN AT69
J 2
(-5510 2135);
DISPLAY 0.489362 (-5510 2135);
PAINT MONO (-5510 2135);
FORCEPROP 0 LASTPIN (-5500 2025) $PN AU69
J 2
(-5510 2035);
DISPLAY 0.489362 (-5510 2035);
PAINT MONO (-5510 2035);
FORCEPROP 0 LASTPIN (-5500 2825) $PN AV70
J 2
(-5510 2835);
DISPLAY 0.489362 (-5510 2835);
PAINT MONO (-5510 2835);
FORCEPROP 0 LASTPIN (-5500 2775) $PN AW69
J 2
(-5510 2785);
DISPLAY 0.489362 (-5510 2785);
PAINT MONO (-5510 2785);
FORCEPROP 0 LASTPIN (-5500 2675) $PN BN69
J 2
(-5510 2685);
DISPLAY 0.489362 (-5510 2685);
PAINT MONO (-5510 2685);
FORCEPROP 0 LASTPIN (-5500 1675) $PN AU71
J 2
(-5510 1685);
DISPLAY 0.489362 (-5510 1685);
PAINT MONO (-5510 1685);
FORCEPROP 0 LASTPIN (-5500 1625) $PN AV69
J 2
(-5510 1635);
DISPLAY 0.489362 (-5510 1635);
PAINT MONO (-5510 1635);
FORCEPROP 0 LASTPIN (-5500 1525) $PN BP69
J 2
(-5510 1535);
DISPLAY 0.489362 (-5510 1535);
PAINT MONO (-5510 1535);
FORCEPROP 0 LASTPIN (-5500 3825) $PN AW71
J 2
(-5510 3835);
DISPLAY 0.489362 (-5510 3835);
PAINT MONO (-5510 3835);
FORCEPROP 0 LASTPIN (-5500 3775) $PN AY70
J 2
(-5510 3785);
DISPLAY 0.489362 (-5510 3785);
PAINT MONO (-5510 3785);
FORCEPROP 0 LASTPIN (-5500 3725) $PN AY69
J 2
(-5510 3735);
DISPLAY 0.489362 (-5510 3735);
PAINT MONO (-5510 3735);
FORCEPROP 0 LASTPIN (-5500 3675) $PN BA69
J 2
(-5510 3685);
DISPLAY 0.489362 (-5510 3685);
PAINT MONO (-5510 3685);
FORCEPROP 0 LASTPIN (-5500 3625) $PN BA71
J 2
(-5510 3635);
DISPLAY 0.489362 (-5510 3635);
PAINT MONO (-5510 3635);
FORCEPROP 0 LASTPIN (-5500 3575) $PN BB70
J 2
(-5510 3585);
DISPLAY 0.489362 (-5510 3585);
PAINT MONO (-5510 3585);
FORCEPROP 0 LASTPIN (-5500 3525) $PN BB69
J 2
(-5510 3535);
DISPLAY 0.489362 (-5510 3535);
PAINT MONO (-5510 3535);
FORCEPROP 0 LASTPIN (-3900 2375) $PN AJ71
J 0
(-3890 2385);
DISPLAY 0.489362 (-3890 2385);
PAINT MONO (-3890 2385);
FORCEPROP 0 LASTPIN (-3900 2325) $PN AK69
J 0
(-3890 2335);
DISPLAY 0.489362 (-3890 2335);
PAINT MONO (-3890 2335);
FORCEPROP 0 LASTPIN (-3900 2275) $PN AK70
J 0
(-3890 2285);
DISPLAY 0.489362 (-3890 2285);
PAINT MONO (-3890 2285);
FORCEPROP 0 LASTPIN (-3900 2225) $PN AL69
J 0
(-3890 2235);
DISPLAY 0.489362 (-3890 2235);
PAINT MONO (-3890 2235);
FORCEPROP 0 LASTPIN (-3900 2175) $PN AN71
J 0
(-3890 2185);
DISPLAY 0.489362 (-3890 2185);
PAINT MONO (-3890 2185);
FORCEPROP 0 LASTPIN (-3900 2125) $PN AP69
J 0
(-3890 2135);
DISPLAY 0.489362 (-3890 2135);
PAINT MONO (-3890 2135);
FORCEPROP 0 LASTPIN (-3900 2075) $PN AP70
J 0
(-3890 2085);
DISPLAY 0.489362 (-3890 2085);
PAINT MONO (-3890 2085);
FORCEPROP 0 LASTPIN (-3900 2025) $PN AR69
J 0
(-3890 2035);
DISPLAY 0.489362 (-3890 2035);
PAINT MONO (-3890 2035);
FORCEPROP 0 LASTPIN (-3900 5975) $PN E71
J 0
(-3890 5985);
DISPLAY 0.489362 (-3890 5985);
PAINT MONO (-3890 5985);
FORCEPROP 0 LASTPIN (-3900 5925) $PN F69
J 0
(-3890 5935);
DISPLAY 0.489362 (-3890 5935);
PAINT MONO (-3890 5935);
FORCEPROP 0 LASTPIN (-3900 5875) $PN F70
J 0
(-3890 5885);
DISPLAY 0.489362 (-3890 5885);
PAINT MONO (-3890 5885);
FORCEPROP 0 LASTPIN (-3900 5825) $PN G69
J 0
(-3890 5835);
DISPLAY 0.489362 (-3890 5835);
PAINT MONO (-3890 5835);
FORCEPROP 0 LASTPIN (-3900 5775) $PN J71
J 0
(-3890 5785);
DISPLAY 0.489362 (-3890 5785);
PAINT MONO (-3890 5785);
FORCEPROP 0 LASTPIN (-3900 5725) $PN K69
J 0
(-3890 5735);
DISPLAY 0.489362 (-3890 5735);
PAINT MONO (-3890 5735);
FORCEPROP 0 LASTPIN (-3900 5675) $PN K70
J 0
(-3890 5685);
DISPLAY 0.489362 (-3890 5685);
PAINT MONO (-3890 5685);
FORCEPROP 0 LASTPIN (-3900 5625) $PN L69
J 0
(-3890 5635);
DISPLAY 0.489362 (-3890 5635);
PAINT MONO (-3890 5635);
FORCEPROP 0 LASTPIN (-3900 5525) $PN L71
J 0
(-3890 5535);
DISPLAY 0.489362 (-3890 5535);
PAINT MONO (-3890 5535);
FORCEPROP 0 LASTPIN (-3900 5475) $PN M69
J 0
(-3890 5485);
DISPLAY 0.489362 (-3890 5485);
PAINT MONO (-3890 5485);
FORCEPROP 0 LASTPIN (-3900 5425) $PN M70
J 0
(-3890 5435);
DISPLAY 0.489362 (-3890 5435);
PAINT MONO (-3890 5435);
FORCEPROP 0 LASTPIN (-3900 5375) $PN N69
J 0
(-3890 5385);
DISPLAY 0.489362 (-3890 5385);
PAINT MONO (-3890 5385);
FORCEPROP 0 LASTPIN (-3900 5325) $PN R71
J 0
(-3890 5335);
DISPLAY 0.489362 (-3890 5335);
PAINT MONO (-3890 5335);
FORCEPROP 0 LASTPIN (-3900 5275) $PN T69
J 0
(-3890 5285);
DISPLAY 0.489362 (-3890 5285);
PAINT MONO (-3890 5285);
FORCEPROP 0 LASTPIN (-3900 5225) $PN T70
J 0
(-3890 5235);
DISPLAY 0.489362 (-3890 5235);
PAINT MONO (-3890 5235);
FORCEPROP 0 LASTPIN (-3900 5175) $PN U69
J 0
(-3890 5185);
DISPLAY 0.489362 (-3890 5185);
PAINT MONO (-3890 5185);
FORCEPROP 0 LASTPIN (-3900 5075) $PN U71
J 0
(-3890 5085);
DISPLAY 0.489362 (-3890 5085);
PAINT MONO (-3890 5085);
FORCEPROP 0 LASTPIN (-3900 5025) $PN V69
J 0
(-3890 5035);
DISPLAY 0.489362 (-3890 5035);
PAINT MONO (-3890 5035);
FORCEPROP 0 LASTPIN (-3900 4975) $PN V70
J 0
(-3890 4985);
DISPLAY 0.489362 (-3890 4985);
PAINT MONO (-3890 4985);
FORCEPROP 0 LASTPIN (-3900 4925) $PN W69
J 0
(-3890 4935);
DISPLAY 0.489362 (-3890 4935);
PAINT MONO (-3890 4935);
FORCEPROP 0 LASTPIN (-3900 4875) $PN AA71
J 0
(-3890 4885);
DISPLAY 0.489362 (-3890 4885);
PAINT MONO (-3890 4885);
FORCEPROP 0 LASTPIN (-3900 4825) $PN AB69
J 0
(-3890 4835);
DISPLAY 0.489362 (-3890 4835);
PAINT MONO (-3890 4835);
FORCEPROP 0 LASTPIN (-3900 4775) $PN AB70
J 0
(-3890 4785);
DISPLAY 0.489362 (-3890 4785);
PAINT MONO (-3890 4785);
FORCEPROP 0 LASTPIN (-3900 4725) $PN AC69
J 0
(-3890 4735);
DISPLAY 0.489362 (-3890 4735);
PAINT MONO (-3890 4735);
FORCEPROP 0 LASTPIN (-3900 4625) $PN AC71
J 0
(-3890 4635);
DISPLAY 0.489362 (-3890 4635);
PAINT MONO (-3890 4635);
FORCEPROP 0 LASTPIN (-3900 4575) $PN AD69
J 0
(-3890 4585);
DISPLAY 0.489362 (-3890 4585);
PAINT MONO (-3890 4585);
FORCEPROP 0 LASTPIN (-3900 4525) $PN AD70
J 0
(-3890 4535);
DISPLAY 0.489362 (-3890 4535);
PAINT MONO (-3890 4535);
FORCEPROP 0 LASTPIN (-3900 4475) $PN AE69
J 0
(-3890 4485);
DISPLAY 0.489362 (-3890 4485);
PAINT MONO (-3890 4485);
FORCEPROP 0 LASTPIN (-3900 4425) $PN AG71
J 0
(-3890 4435);
DISPLAY 0.489362 (-3890 4435);
PAINT MONO (-3890 4435);
FORCEPROP 0 LASTPIN (-3900 4375) $PN AH69
J 0
(-3890 4385);
DISPLAY 0.489362 (-3890 4385);
PAINT MONO (-3890 4385);
FORCEPROP 0 LASTPIN (-3900 4325) $PN AH70
J 0
(-3890 4335);
DISPLAY 0.489362 (-3890 4335);
PAINT MONO (-3890 4335);
FORCEPROP 0 LASTPIN (-3900 4275) $PN AJ69
J 0
(-3890 4285);
DISPLAY 0.489362 (-3890 4285);
PAINT MONO (-3890 4285);
FORCEPROP 0 LASTPIN (-5500 5975) $PN G71
J 2
(-5510 5985);
DISPLAY 0.489362 (-5510 5985);
PAINT MONO (-5510 5985);
FORCEPROP 0 LASTPIN (-5500 5875) $PN N71
J 2
(-5510 5885);
DISPLAY 0.489362 (-5510 5885);
PAINT MONO (-5510 5885);
FORCEPROP 0 LASTPIN (-5500 5775) $PN W71
J 2
(-5510 5785);
DISPLAY 0.489362 (-5510 5785);
PAINT MONO (-5510 5785);
FORCEPROP 0 LASTPIN (-5500 5675) $PN AE71
J 2
(-5510 5685);
DISPLAY 0.489362 (-5510 5685);
PAINT MONO (-5510 5685);
FORCEPROP 0 LASTPIN (-5500 5575) $PN AL71
J 2
(-5510 5585);
DISPLAY 0.489362 (-5510 5585);
PAINT MONO (-5510 5585);
FORCEPROP 0 LASTPIN (-5500 5475) $PN J69
J 2
(-5510 5485);
DISPLAY 0.489362 (-5510 5485);
PAINT MONO (-5510 5485);
FORCEPROP 0 LASTPIN (-5500 5375) $PN R69
J 2
(-5510 5385);
DISPLAY 0.489362 (-5510 5385);
PAINT MONO (-5510 5385);
FORCEPROP 0 LASTPIN (-5500 5275) $PN AA69
J 2
(-5510 5285);
DISPLAY 0.489362 (-5510 5285);
PAINT MONO (-5510 5285);
FORCEPROP 0 LASTPIN (-5500 5175) $PN AG69
J 2
(-5510 5185);
DISPLAY 0.489362 (-5510 5185);
PAINT MONO (-5510 5185);
FORCEPROP 0 LASTPIN (-5500 5075) $PN AN69
J 2
(-5510 5085);
DISPLAY 0.489362 (-5510 5085);
PAINT MONO (-5510 5085);
FORCEPROP 0 LASTPIN (-5500 5925) $PN H70
J 2
(-5510 5935);
DISPLAY 0.489362 (-5510 5935);
PAINT MONO (-5510 5935);
FORCEPROP 0 LASTPIN (-5500 5825) $PN P70
J 2
(-5510 5835);
DISPLAY 0.489362 (-5510 5835);
PAINT MONO (-5510 5835);
FORCEPROP 0 LASTPIN (-5500 5725) $PN Y70
J 2
(-5510 5735);
DISPLAY 0.489362 (-5510 5735);
PAINT MONO (-5510 5735);
FORCEPROP 0 LASTPIN (-5500 5625) $PN AF70
J 2
(-5510 5635);
DISPLAY 0.489362 (-5510 5635);
PAINT MONO (-5510 5635);
FORCEPROP 0 LASTPIN (-5500 5525) $PN AM70
J 2
(-5510 5535);
DISPLAY 0.489362 (-5510 5535);
PAINT MONO (-5510 5535);
FORCEPROP 0 LASTPIN (-5500 5425) $PN H69
J 2
(-5510 5435);
DISPLAY 0.489362 (-5510 5435);
PAINT MONO (-5510 5435);
FORCEPROP 0 LASTPIN (-5500 5325) $PN P69
J 2
(-5510 5335);
DISPLAY 0.489362 (-5510 5335);
PAINT MONO (-5510 5335);
FORCEPROP 0 LASTPIN (-5500 5225) $PN Y69
J 2
(-5510 5235);
DISPLAY 0.489362 (-5510 5235);
PAINT MONO (-5510 5235);
FORCEPROP 0 LASTPIN (-5500 5125) $PN AF69
J 2
(-5510 5135);
DISPLAY 0.489362 (-5510 5135);
PAINT MONO (-5510 5135);
FORCEPROP 0 LASTPIN (-5500 5025) $PN AM69
J 2
(-5510 5035);
DISPLAY 0.489362 (-5510 5035);
PAINT MONO (-5510 5035);
FORCEPROP 0 LASTPIN (-5500 2575) $PN BC69
J 2
(-5510 2585);
DISPLAY 0.489362 (-5510 2585);
PAINT MONO (-5510 2585);
FORCEPROP 0 LASTPIN (-5500 2475) $PN BM69
J 2
(-5510 2485);
DISPLAY 0.489362 (-5510 2485);
PAINT MONO (-5510 2485);
FORCEPROP 0 LASTPIN (-5500 2425) $PN BN71
J 2
(-5510 2435);
DISPLAY 0.489362 (-5510 2435);
PAINT MONO (-5510 2435);
FORCEPROP 0 LASTPIN (-5500 2325) $PN BP70
J 2
(-5510 2335);
DISPLAY 0.489362 (-5510 2335);
PAINT MONO (-5510 2335);
FORCEPROP 0 LASTPIN (-5500 1425) $PN BL69
J 2
(-5510 1435);
DISPLAY 0.489362 (-5510 1435);
PAINT MONO (-5510 1435);
FORCEPROP 0 LASTPIN (-5500 1375) $PN BM70
J 2
(-5510 1385);
DISPLAY 0.489362 (-5510 1385);
PAINT MONO (-5510 1385);
FORCEPROP 0 LASTPIN (-5500 1275) $PN BR71
J 2
(-5510 1285);
DISPLAY 0.489362 (-5510 1285);
PAINT MONO (-5510 1285);
FORCEPROP 0 LASTPIN (-5500 3425) $PN BG69
J 2
(-5510 3435);
DISPLAY 0.489362 (-5510 3435);
PAINT MONO (-5510 3435);
FORCEPROP 0 LASTPIN (-5500 3375) $PN BH69
J 2
(-5510 3385);
DISPLAY 0.489362 (-5510 3385);
PAINT MONO (-5510 3385);
FORCEPROP 0 LASTPIN (-5500 3325) $PN BH70
J 2
(-5510 3335);
DISPLAY 0.489362 (-5510 3335);
PAINT MONO (-5510 3335);
FORCEPROP 0 LASTPIN (-5500 3275) $PN BJ71
J 2
(-5510 3285);
DISPLAY 0.489362 (-5510 3285);
PAINT MONO (-5510 3285);
FORCEPROP 0 LASTPIN (-5500 3225) $PN BJ69
J 2
(-5510 3235);
DISPLAY 0.489362 (-5510 3235);
PAINT MONO (-5510 3235);
FORCEPROP 0 LASTPIN (-5500 3175) $PN BK69
J 2
(-5510 3185);
DISPLAY 0.489362 (-5510 3185);
PAINT MONO (-5510 3185);
FORCEPROP 0 LASTPIN (-5500 3125) $PN BK70
J 2
(-5510 3135);
DISPLAY 0.489362 (-5510 3135);
PAINT MONO (-5510 3135);
FORCEPROP 0 LASTPIN (-3900 1925) $PN BY70
J 0
(-3890 1935);
DISPLAY 0.489362 (-3890 1935);
PAINT MONO (-3890 1935);
FORCEPROP 0 LASTPIN (-3900 1875) $PN CA69
J 0
(-3890 1885);
DISPLAY 0.489362 (-3890 1885);
PAINT MONO (-3890 1885);
FORCEPROP 0 LASTPIN (-3900 1825) $PN CA71
J 0
(-3890 1835);
DISPLAY 0.489362 (-3890 1835);
PAINT MONO (-3890 1835);
FORCEPROP 0 LASTPIN (-3900 1775) $PN CB69
J 0
(-3890 1785);
DISPLAY 0.489362 (-3890 1785);
PAINT MONO (-3890 1785);
FORCEPROP 0 LASTPIN (-3900 1725) $PN BT70
J 0
(-3890 1735);
DISPLAY 0.489362 (-3890 1735);
PAINT MONO (-3890 1735);
FORCEPROP 0 LASTPIN (-3900 1675) $PN BU69
J 0
(-3890 1685);
DISPLAY 0.489362 (-3890 1685);
PAINT MONO (-3890 1685);
FORCEPROP 0 LASTPIN (-3900 1625) $PN BU71
J 0
(-3890 1635);
DISPLAY 0.489362 (-3890 1635);
PAINT MONO (-3890 1635);
FORCEPROP 0 LASTPIN (-3900 1575) $PN BV69
J 0
(-3890 1585);
DISPLAY 0.489362 (-3890 1585);
PAINT MONO (-3890 1585);
FORCEPROP 0 LASTPIN (-3900 4175) $PN CB70
J 0
(-3890 4185);
DISPLAY 0.489362 (-3890 4185);
PAINT MONO (-3890 4185);
FORCEPROP 0 LASTPIN (-3900 4125) $PN CC69
J 0
(-3890 4135);
DISPLAY 0.489362 (-3890 4135);
PAINT MONO (-3890 4135);
FORCEPROP 0 LASTPIN (-3900 4075) $PN CC71
J 0
(-3890 4085);
DISPLAY 0.489362 (-3890 4085);
PAINT MONO (-3890 4085);
FORCEPROP 0 LASTPIN (-3900 4025) $PN CD69
J 0
(-3890 4035);
DISPLAY 0.489362 (-3890 4035);
PAINT MONO (-3890 4035);
FORCEPROP 0 LASTPIN (-3900 3975) $PN CF70
J 0
(-3890 3985);
DISPLAY 0.489362 (-3890 3985);
PAINT MONO (-3890 3985);
FORCEPROP 0 LASTPIN (-3900 3925) $PN CG69
J 0
(-3890 3935);
DISPLAY 0.489362 (-3890 3935);
PAINT MONO (-3890 3935);
FORCEPROP 0 LASTPIN (-3900 3875) $PN CG71
J 0
(-3890 3885);
DISPLAY 0.489362 (-3890 3885);
PAINT MONO (-3890 3885);
FORCEPROP 0 LASTPIN (-3900 3825) $PN CH69
J 0
(-3890 3835);
DISPLAY 0.489362 (-3890 3835);
PAINT MONO (-3890 3835);
FORCEPROP 0 LASTPIN (-3900 3725) $PN CH70
J 0
(-3890 3735);
DISPLAY 0.489362 (-3890 3735);
PAINT MONO (-3890 3735);
FORCEPROP 0 LASTPIN (-3900 3675) $PN CJ69
J 0
(-3890 3685);
DISPLAY 0.489362 (-3890 3685);
PAINT MONO (-3890 3685);
FORCEPROP 0 LASTPIN (-3900 3625) $PN CJ71
J 0
(-3890 3635);
DISPLAY 0.489362 (-3890 3635);
PAINT MONO (-3890 3635);
FORCEPROP 0 LASTPIN (-3900 3575) $PN CK69
J 0
(-3890 3585);
DISPLAY 0.489362 (-3890 3585);
PAINT MONO (-3890 3585);
FORCEPROP 0 LASTPIN (-3900 3525) $PN CM70
J 0
(-3890 3535);
DISPLAY 0.489362 (-3890 3535);
PAINT MONO (-3890 3535);
FORCEPROP 0 LASTPIN (-3900 3475) $PN CN69
J 0
(-3890 3485);
DISPLAY 0.489362 (-3890 3485);
PAINT MONO (-3890 3485);
FORCEPROP 0 LASTPIN (-3900 3425) $PN CN71
J 0
(-3890 3435);
DISPLAY 0.489362 (-3890 3435);
PAINT MONO (-3890 3435);
FORCEPROP 0 LASTPIN (-3900 3375) $PN CP69
J 0
(-3890 3385);
DISPLAY 0.489362 (-3890 3385);
PAINT MONO (-3890 3385);
FORCEPROP 0 LASTPIN (-3900 3275) $PN CP70
J 0
(-3890 3285);
DISPLAY 0.489362 (-3890 3285);
PAINT MONO (-3890 3285);
FORCEPROP 0 LASTPIN (-3900 3225) $PN CR69
J 0
(-3890 3235);
DISPLAY 0.489362 (-3890 3235);
PAINT MONO (-3890 3235);
FORCEPROP 0 LASTPIN (-3900 3175) $PN CR71
J 0
(-3890 3185);
DISPLAY 0.489362 (-3890 3185);
PAINT MONO (-3890 3185);
FORCEPROP 0 LASTPIN (-3900 3125) $PN CT69
J 0
(-3890 3135);
DISPLAY 0.489362 (-3890 3135);
PAINT MONO (-3890 3135);
FORCEPROP 0 LASTPIN (-3900 3075) $PN CV70
J 0
(-3890 3085);
DISPLAY 0.489362 (-3890 3085);
PAINT MONO (-3890 3085);
FORCEPROP 0 LASTPIN (-3900 3025) $PN CW69
J 0
(-3890 3035);
DISPLAY 0.489362 (-3890 3035);
PAINT MONO (-3890 3035);
FORCEPROP 0 LASTPIN (-3900 2975) $PN CW71
J 0
(-3890 2985);
DISPLAY 0.489362 (-3890 2985);
PAINT MONO (-3890 2985);
FORCEPROP 0 LASTPIN (-3900 2925) $PN CY69
J 0
(-3890 2935);
DISPLAY 0.489362 (-3890 2935);
PAINT MONO (-3890 2935);
FORCEPROP 0 LASTPIN (-3900 2825) $PN CY70
J 0
(-3890 2835);
DISPLAY 0.489362 (-3890 2835);
PAINT MONO (-3890 2835);
FORCEPROP 0 LASTPIN (-3900 2775) $PN DA69
J 0
(-3890 2785);
DISPLAY 0.489362 (-3890 2785);
PAINT MONO (-3890 2785);
FORCEPROP 0 LASTPIN (-3900 2725) $PN DA71
J 0
(-3890 2735);
DISPLAY 0.489362 (-3890 2735);
PAINT MONO (-3890 2735);
FORCEPROP 0 LASTPIN (-3900 2675) $PN DB69
J 0
(-3890 2685);
DISPLAY 0.489362 (-3890 2685);
PAINT MONO (-3890 2685);
FORCEPROP 0 LASTPIN (-3900 2625) $PN DD70
J 0
(-3890 2635);
DISPLAY 0.489362 (-3890 2635);
PAINT MONO (-3890 2635);
FORCEPROP 0 LASTPIN (-3900 2575) $PN DE69
J 0
(-3890 2585);
DISPLAY 0.489362 (-3890 2585);
PAINT MONO (-3890 2585);
FORCEPROP 0 LASTPIN (-3900 2525) $PN DE71
J 0
(-3890 2535);
DISPLAY 0.489362 (-3890 2535);
PAINT MONO (-3890 2535);
FORCEPROP 0 LASTPIN (-3900 2475) $PN DF69
J 0
(-3890 2485);
DISPLAY 0.489362 (-3890 2485);
PAINT MONO (-3890 2485);
FORCEPROP 0 LASTPIN (-5500 4925) $PN CD70
J 2
(-5510 4935);
DISPLAY 0.489362 (-5510 4935);
PAINT MONO (-5510 4935);
FORCEPROP 0 LASTPIN (-5500 4825) $PN CK70
J 2
(-5510 4835);
DISPLAY 0.489362 (-5510 4835);
PAINT MONO (-5510 4835);
FORCEPROP 0 LASTPIN (-5500 4725) $PN CT70
J 2
(-5510 4735);
DISPLAY 0.489362 (-5510 4735);
PAINT MONO (-5510 4735);
FORCEPROP 0 LASTPIN (-5500 4625) $PN DB70
J 2
(-5510 4635);
DISPLAY 0.489362 (-5510 4635);
PAINT MONO (-5510 4635);
FORCEPROP 0 LASTPIN (-5500 4525) $PN BY69
J 2
(-5510 4535);
DISPLAY 0.489362 (-5510 4535);
PAINT MONO (-5510 4535);
FORCEPROP 0 LASTPIN (-5500 4425) $PN CF69
J 2
(-5510 4435);
DISPLAY 0.489362 (-5510 4435);
PAINT MONO (-5510 4435);
FORCEPROP 0 LASTPIN (-5500 4325) $PN CM69
J 2
(-5510 4335);
DISPLAY 0.489362 (-5510 4335);
PAINT MONO (-5510 4335);
FORCEPROP 0 LASTPIN (-5500 4225) $PN CV69
J 2
(-5510 4235);
DISPLAY 0.489362 (-5510 4235);
PAINT MONO (-5510 4235);
FORCEPROP 0 LASTPIN (-5500 4125) $PN DD69
J 2
(-5510 4135);
DISPLAY 0.489362 (-5510 4135);
PAINT MONO (-5510 4135);
FORCEPROP 0 LASTPIN (-5500 4025) $PN BV70
J 2
(-5510 4035);
DISPLAY 0.489362 (-5510 4035);
PAINT MONO (-5510 4035);
FORCEPROP 0 LASTPIN (-5500 4875) $PN CE71
J 2
(-5510 4885);
DISPLAY 0.489362 (-5510 4885);
PAINT MONO (-5510 4885);
FORCEPROP 0 LASTPIN (-5500 4775) $PN CL71
J 2
(-5510 4785);
DISPLAY 0.489362 (-5510 4785);
PAINT MONO (-5510 4785);
FORCEPROP 0 LASTPIN (-5500 4675) $PN CU71
J 2
(-5510 4685);
DISPLAY 0.489362 (-5510 4685);
PAINT MONO (-5510 4685);
FORCEPROP 0 LASTPIN (-5500 4575) $PN DC71
J 2
(-5510 4585);
DISPLAY 0.489362 (-5510 4585);
PAINT MONO (-5510 4585);
FORCEPROP 0 LASTPIN (-5500 4475) $PN BW69
J 2
(-5510 4485);
DISPLAY 0.489362 (-5510 4485);
PAINT MONO (-5510 4485);
FORCEPROP 0 LASTPIN (-5500 4375) $PN CE69
J 2
(-5510 4385);
DISPLAY 0.489362 (-5510 4385);
PAINT MONO (-5510 4385);
FORCEPROP 0 LASTPIN (-5500 4275) $PN CL69
J 2
(-5510 4285);
DISPLAY 0.489362 (-5510 4285);
PAINT MONO (-5510 4285);
FORCEPROP 0 LASTPIN (-5500 4175) $PN CU69
J 2
(-5510 4185);
DISPLAY 0.489362 (-5510 4185);
PAINT MONO (-5510 4185);
FORCEPROP 0 LASTPIN (-5500 4075) $PN DC69
J 2
(-5510 4085);
DISPLAY 0.489362 (-5510 4085);
PAINT MONO (-5510 4085);
FORCEPROP 0 LASTPIN (-5500 3975) $PN BW71
J 2
(-5510 3985);
DISPLAY 0.489362 (-5510 3985);
PAINT MONO (-5510 3985);
FORCEPROP 0 LASTPIN (-5500 2225) $PN BL71
J 2
(-5510 2235);
DISPLAY 0.489362 (-5510 2235);
PAINT MONO (-5510 2235);
FORCEPROP 0 LASTPIN (-5500 1175) $PN BF69
J 2
(-5510 1185);
DISPLAY 0.489362 (-5510 1185);
PAINT MONO (-5510 1185);
FORCEPROP 2 LAST PART_TYPE SMLF
J 0
(-5350 6375);
DISPLAY 1.021277 (-5350 6375);
FORCEPROP 1 LAST MATERIAL IO
J 0
(-5345 6157);
DISPLAY 0.489362 (-5345 6157);
PAINT SKYBLUE (-5345 6157);
FORCEPROP 2 LAST VALUE SOCKET6096_13568-001
J 0
(-5350 6275);
DISPLAY 0.489362 (-5350 6275);
PAINT SKYBLUE (-5350 6275);
FORCEPROP 2 LAST CDS_LIB pure_quanta
J 0
(-4700 3600);
DISPLAY INVISIBLE (-4700 3600);
FORCEPROP 1 LAST CDS_LMAN_SYM_OUTLINE -650,2525,650,-2525
J 0
(-4700 3600);
DISPLAY 0.468085 (-4700 3600);
PAINT GREEN (-4700 3600);
DISPLAY INVISIBLE (-4700 3600);
FORCEPROP 1 LAST NEEDS_NO_SIZE TRUE
J 0
(-4700 3600);
DISPLAY 0.723404 (-4700 3600);
PAINT GREEN (-4700 3600);
DISPLAY INVISIBLE (-4700 3600);
FORCEPROP 1 LAST PATH I159
J 0
(-4700 3600);
DISPLAY 0.723404 (-4700 3600);
PAINT GREEN (-4700 3600);
DISPLAY INVISIBLE (-4700 3600);
FORCEPROP 1 LAST PART_NUMBER DGA^6000030
J 0
(-5345 6284);
DISPLAY 0.489362 (-5345 6284);
PAINT SKYBLUE (-5345 6284);
DISPLAY INVISIBLE (-5345 6284);
FORCEADD OFFPAGE..3
(-2700 6000);
FORCEPROP 2 LAST $XR0 102 
J 0
(-2486 6000);
DISPLAY 0.638298 (-2486 6000);
PAINT MONO (-2486 6000);
FORCEPROP 2 LAST CDS_LIB mstr_standard
J 0
(-2700 6000);
DISPLAY 0.723404 (-2700 6000);
PAINT MONO (-2700 6000);
DISPLAY INVISIBLE (-2700 6000);
FORCEPROP 1 LAST OFFPAGE TRUE
J 0
(-2375 5875);
DISPLAY 0.872340 (-2375 5875);
PAINT GREEN (-2375 5875);
DISPLAY INVISIBLE (-2375 5875);
FORCEPROP 1 LAST COMMENT_BODY TRUE
J 0
(-2750 5900);
DISPLAY 0.872340 (-2750 5900);
PAINT GREEN (-2750 5900);
DISPLAY INVISIBLE (-2750 5900);
FORCEPROP 2 LAST PATH I160
J 0
(-2475 6050);
DISPLAY 1.021277 (-2475 6050);
DISPLAY INVISIBLE (-2475 6050);
FORCEADD OFFPAGE..3
(-2700 4200);
FORCEPROP 2 LAST $XR0 102 
J 0
(-2486 4200);
DISPLAY 0.638298 (-2486 4200);
PAINT MONO (-2486 4200);
FORCEPROP 2 LAST CDS_LIB mstr_standard
J 0
(-2700 4200);
DISPLAY 0.723404 (-2700 4200);
PAINT MONO (-2700 4200);
DISPLAY INVISIBLE (-2700 4200);
FORCEPROP 1 LAST OFFPAGE TRUE
J 0
(-2375 4075);
DISPLAY 0.872340 (-2375 4075);
PAINT GREEN (-2375 4075);
DISPLAY INVISIBLE (-2375 4075);
FORCEPROP 1 LAST COMMENT_BODY TRUE
J 0
(-2750 4100);
DISPLAY 0.872340 (-2750 4100);
PAINT GREEN (-2750 4100);
DISPLAY INVISIBLE (-2750 4100);
FORCEPROP 2 LAST PATH I161
J 0
(-2475 4250);
DISPLAY 1.021277 (-2475 4250);
DISPLAY INVISIBLE (-2475 4250);
FORCEADD TAP..1
(-3425 5975);
FORCEPROP 3 LASTPIN (-3475 5975) SIG_NAME M_E_CPU1_SA_DQ<0>
J 0
(-3465 5985);
DISPLAY 0.659574 (-3465 5985);
PAINT MONO (-3465 5985);
DISPLAY INVISIBLE (-3465 5985);
FORCEPROP 1 LASTPIN (-3475 5975) BN 0
J 0
(-3487 5983);
DISPLAY 0.489362 (-3487 5983);
PAINT GREEN (-3487 5983);
FORCEPROP 2 LAST CDS_LIB mstr_standard
J 0
(-3425 5975);
DISPLAY 0.723404 (-3425 5975);
PAINT MONO (-3425 5975);
DISPLAY INVISIBLE (-3425 5975);
FORCEPROP 1 LAST BODY_TYPE PLUMBING
J 0
(-3425 6025);
DISPLAY 0.872340 (-3425 6025);
PAINT GREEN (-3425 6025);
DISPLAY INVISIBLE (-3425 6025);
FORCEPROP 1 LAST HDL_TAP TRUE
J 0
(-3100 5850);
DISPLAY 0.872340 (-3100 5850);
DISPLAY INVISIBLE (-3100 5850);
FORCEPROP 1 LAST PATH I162
J 0
(-3427 5975);
DISPLAY 0.872340 (-3427 5975);
PAINT GREEN (-3427 5975);
DISPLAY INVISIBLE (-3427 5975);
FORCEADD TAP..1
(-3425 5925);
FORCEPROP 3 LASTPIN (-3475 5925) SIG_NAME M_E_CPU1_SA_DQ<1>
J 0
(-3465 5935);
DISPLAY 0.659574 (-3465 5935);
PAINT MONO (-3465 5935);
DISPLAY INVISIBLE (-3465 5935);
FORCEPROP 1 LASTPIN (-3475 5925) BN 1
J 0
(-3487 5933);
DISPLAY 0.489362 (-3487 5933);
PAINT GREEN (-3487 5933);
FORCEPROP 2 LAST CDS_LIB mstr_standard
J 0
(-3425 5925);
DISPLAY 0.723404 (-3425 5925);
PAINT MONO (-3425 5925);
DISPLAY INVISIBLE (-3425 5925);
FORCEPROP 1 LAST BODY_TYPE PLUMBING
J 0
(-3425 5975);
DISPLAY 0.872340 (-3425 5975);
PAINT GREEN (-3425 5975);
DISPLAY INVISIBLE (-3425 5975);
FORCEPROP 1 LAST HDL_TAP TRUE
J 0
(-3100 5800);
DISPLAY 0.872340 (-3100 5800);
DISPLAY INVISIBLE (-3100 5800);
FORCEPROP 1 LAST PATH I163
J 0
(-3427 5925);
DISPLAY 0.872340 (-3427 5925);
PAINT GREEN (-3427 5925);
DISPLAY INVISIBLE (-3427 5925);
FORCEADD TAP..1
(-3425 5875);
FORCEPROP 3 LASTPIN (-3475 5875) SIG_NAME M_E_CPU1_SA_DQ<2>
J 0
(-3465 5885);
DISPLAY 0.659574 (-3465 5885);
PAINT MONO (-3465 5885);
DISPLAY INVISIBLE (-3465 5885);
FORCEPROP 1 LASTPIN (-3475 5875) BN 2
J 0
(-3487 5883);
DISPLAY 0.489362 (-3487 5883);
PAINT GREEN (-3487 5883);
FORCEPROP 2 LAST CDS_LIB mstr_standard
J 0
(-3425 5875);
DISPLAY 0.723404 (-3425 5875);
PAINT MONO (-3425 5875);
DISPLAY INVISIBLE (-3425 5875);
FORCEPROP 1 LAST BODY_TYPE PLUMBING
J 0
(-3425 5925);
DISPLAY 0.872340 (-3425 5925);
PAINT GREEN (-3425 5925);
DISPLAY INVISIBLE (-3425 5925);
FORCEPROP 1 LAST HDL_TAP TRUE
J 0
(-3100 5750);
DISPLAY 0.872340 (-3100 5750);
DISPLAY INVISIBLE (-3100 5750);
FORCEPROP 1 LAST PATH I164
J 0
(-3427 5875);
DISPLAY 0.872340 (-3427 5875);
PAINT GREEN (-3427 5875);
DISPLAY INVISIBLE (-3427 5875);
FORCEADD TAP..1
(-3425 5825);
FORCEPROP 3 LASTPIN (-3475 5825) SIG_NAME M_E_CPU1_SA_DQ<3>
J 0
(-3465 5835);
DISPLAY 0.659574 (-3465 5835);
PAINT MONO (-3465 5835);
DISPLAY INVISIBLE (-3465 5835);
FORCEPROP 1 LASTPIN (-3475 5825) BN 3
J 0
(-3487 5833);
DISPLAY 0.489362 (-3487 5833);
PAINT GREEN (-3487 5833);
FORCEPROP 2 LAST CDS_LIB mstr_standard
J 0
(-3425 5825);
DISPLAY 0.723404 (-3425 5825);
PAINT MONO (-3425 5825);
DISPLAY INVISIBLE (-3425 5825);
FORCEPROP 1 LAST BODY_TYPE PLUMBING
J 0
(-3425 5875);
DISPLAY 0.872340 (-3425 5875);
PAINT GREEN (-3425 5875);
DISPLAY INVISIBLE (-3425 5875);
FORCEPROP 1 LAST HDL_TAP TRUE
J 0
(-3100 5700);
DISPLAY 0.872340 (-3100 5700);
DISPLAY INVISIBLE (-3100 5700);
FORCEPROP 1 LAST PATH I165
J 0
(-3427 5825);
DISPLAY 0.872340 (-3427 5825);
PAINT GREEN (-3427 5825);
DISPLAY INVISIBLE (-3427 5825);
FORCEADD TAP..1
(-3425 5775);
FORCEPROP 3 LASTPIN (-3475 5775) SIG_NAME M_E_CPU1_SA_DQ<4>
J 0
(-3465 5785);
DISPLAY 0.659574 (-3465 5785);
PAINT MONO (-3465 5785);
DISPLAY INVISIBLE (-3465 5785);
FORCEPROP 1 LASTPIN (-3475 5775) BN 4
J 0
(-3487 5783);
DISPLAY 0.489362 (-3487 5783);
PAINT GREEN (-3487 5783);
FORCEPROP 2 LAST CDS_LIB mstr_standard
J 0
(-3425 5775);
DISPLAY 0.723404 (-3425 5775);
PAINT MONO (-3425 5775);
DISPLAY INVISIBLE (-3425 5775);
FORCEPROP 1 LAST BODY_TYPE PLUMBING
J 0
(-3425 5825);
DISPLAY 0.872340 (-3425 5825);
PAINT GREEN (-3425 5825);
DISPLAY INVISIBLE (-3425 5825);
FORCEPROP 1 LAST HDL_TAP TRUE
J 0
(-3100 5650);
DISPLAY 0.872340 (-3100 5650);
DISPLAY INVISIBLE (-3100 5650);
FORCEPROP 1 LAST PATH I166
J 0
(-3427 5775);
DISPLAY 0.872340 (-3427 5775);
PAINT GREEN (-3427 5775);
DISPLAY INVISIBLE (-3427 5775);
FORCEADD TAP..1
(-3425 5725);
FORCEPROP 3 LASTPIN (-3475 5725) SIG_NAME M_E_CPU1_SA_DQ<5>
J 0
(-3465 5735);
DISPLAY 0.659574 (-3465 5735);
PAINT MONO (-3465 5735);
DISPLAY INVISIBLE (-3465 5735);
FORCEPROP 1 LASTPIN (-3475 5725) BN 5
J 0
(-3487 5733);
DISPLAY 0.489362 (-3487 5733);
PAINT GREEN (-3487 5733);
FORCEPROP 2 LAST CDS_LIB mstr_standard
J 0
(-3425 5725);
DISPLAY 0.723404 (-3425 5725);
PAINT MONO (-3425 5725);
DISPLAY INVISIBLE (-3425 5725);
FORCEPROP 1 LAST BODY_TYPE PLUMBING
J 0
(-3425 5775);
DISPLAY 0.872340 (-3425 5775);
PAINT GREEN (-3425 5775);
DISPLAY INVISIBLE (-3425 5775);
FORCEPROP 1 LAST HDL_TAP TRUE
J 0
(-3100 5600);
DISPLAY 0.872340 (-3100 5600);
DISPLAY INVISIBLE (-3100 5600);
FORCEPROP 1 LAST PATH I167
J 0
(-3427 5725);
DISPLAY 0.872340 (-3427 5725);
PAINT GREEN (-3427 5725);
DISPLAY INVISIBLE (-3427 5725);
FORCEADD TAP..1
(-3425 5675);
FORCEPROP 3 LASTPIN (-3475 5675) SIG_NAME M_E_CPU1_SA_DQ<6>
J 0
(-3465 5685);
DISPLAY 0.659574 (-3465 5685);
PAINT MONO (-3465 5685);
DISPLAY INVISIBLE (-3465 5685);
FORCEPROP 1 LASTPIN (-3475 5675) BN 6
J 0
(-3487 5683);
DISPLAY 0.489362 (-3487 5683);
PAINT GREEN (-3487 5683);
FORCEPROP 2 LAST CDS_LIB mstr_standard
J 0
(-3425 5675);
DISPLAY 0.723404 (-3425 5675);
PAINT MONO (-3425 5675);
DISPLAY INVISIBLE (-3425 5675);
FORCEPROP 1 LAST BODY_TYPE PLUMBING
J 0
(-3425 5725);
DISPLAY 0.872340 (-3425 5725);
PAINT GREEN (-3425 5725);
DISPLAY INVISIBLE (-3425 5725);
FORCEPROP 1 LAST HDL_TAP TRUE
J 0
(-3100 5550);
DISPLAY 0.872340 (-3100 5550);
DISPLAY INVISIBLE (-3100 5550);
FORCEPROP 1 LAST PATH I168
J 0
(-3427 5675);
DISPLAY 0.872340 (-3427 5675);
PAINT GREEN (-3427 5675);
DISPLAY INVISIBLE (-3427 5675);
FORCEADD TAP..1
(-3425 5625);
FORCEPROP 3 LASTPIN (-3475 5625) SIG_NAME M_E_CPU1_SA_DQ<7>
J 0
(-3465 5635);
DISPLAY 0.659574 (-3465 5635);
PAINT MONO (-3465 5635);
DISPLAY INVISIBLE (-3465 5635);
FORCEPROP 1 LASTPIN (-3475 5625) BN 7
J 0
(-3487 5633);
DISPLAY 0.489362 (-3487 5633);
PAINT GREEN (-3487 5633);
FORCEPROP 2 LAST CDS_LIB mstr_standard
J 0
(-3425 5625);
DISPLAY 0.723404 (-3425 5625);
PAINT MONO (-3425 5625);
DISPLAY INVISIBLE (-3425 5625);
FORCEPROP 1 LAST BODY_TYPE PLUMBING
J 0
(-3425 5675);
DISPLAY 0.872340 (-3425 5675);
PAINT GREEN (-3425 5675);
DISPLAY INVISIBLE (-3425 5675);
FORCEPROP 1 LAST HDL_TAP TRUE
J 0
(-3100 5500);
DISPLAY 0.872340 (-3100 5500);
DISPLAY INVISIBLE (-3100 5500);
FORCEPROP 1 LAST PATH I169
J 0
(-3427 5625);
DISPLAY 0.872340 (-3427 5625);
PAINT GREEN (-3427 5625);
DISPLAY INVISIBLE (-3427 5625);
FORCEADD TAP..1
(-3425 5525);
FORCEPROP 3 LASTPIN (-3475 5525) SIG_NAME M_E_CPU1_SA_DQ<8>
J 0
(-3465 5535);
DISPLAY 0.659574 (-3465 5535);
PAINT MONO (-3465 5535);
DISPLAY INVISIBLE (-3465 5535);
FORCEPROP 1 LASTPIN (-3475 5525) BN 8
J 0
(-3487 5533);
DISPLAY 0.489362 (-3487 5533);
PAINT GREEN (-3487 5533);
FORCEPROP 2 LAST CDS_LIB mstr_standard
J 0
(-3425 5525);
DISPLAY 0.723404 (-3425 5525);
PAINT MONO (-3425 5525);
DISPLAY INVISIBLE (-3425 5525);
FORCEPROP 1 LAST BODY_TYPE PLUMBING
J 0
(-3425 5575);
DISPLAY 0.872340 (-3425 5575);
PAINT GREEN (-3425 5575);
DISPLAY INVISIBLE (-3425 5575);
FORCEPROP 1 LAST HDL_TAP TRUE
J 0
(-3100 5400);
DISPLAY 0.872340 (-3100 5400);
DISPLAY INVISIBLE (-3100 5400);
FORCEPROP 1 LAST PATH I170
J 0
(-3427 5525);
DISPLAY 0.872340 (-3427 5525);
PAINT GREEN (-3427 5525);
DISPLAY INVISIBLE (-3427 5525);
FORCEADD TAP..1
(-3425 5475);
FORCEPROP 3 LASTPIN (-3475 5475) SIG_NAME M_E_CPU1_SA_DQ<9>
J 0
(-3465 5485);
DISPLAY 0.659574 (-3465 5485);
PAINT MONO (-3465 5485);
DISPLAY INVISIBLE (-3465 5485);
FORCEPROP 1 LASTPIN (-3475 5475) BN 9
J 0
(-3487 5483);
DISPLAY 0.489362 (-3487 5483);
PAINT GREEN (-3487 5483);
FORCEPROP 2 LAST CDS_LIB mstr_standard
J 0
(-3425 5475);
DISPLAY 0.723404 (-3425 5475);
PAINT MONO (-3425 5475);
DISPLAY INVISIBLE (-3425 5475);
FORCEPROP 1 LAST BODY_TYPE PLUMBING
J 0
(-3425 5525);
DISPLAY 0.872340 (-3425 5525);
PAINT GREEN (-3425 5525);
DISPLAY INVISIBLE (-3425 5525);
FORCEPROP 1 LAST HDL_TAP TRUE
J 0
(-3100 5350);
DISPLAY 0.872340 (-3100 5350);
DISPLAY INVISIBLE (-3100 5350);
FORCEPROP 1 LAST PATH I171
J 0
(-3427 5475);
DISPLAY 0.872340 (-3427 5475);
PAINT GREEN (-3427 5475);
DISPLAY INVISIBLE (-3427 5475);
FORCEADD TAP..1
(-3425 5425);
FORCEPROP 3 LASTPIN (-3475 5425) SIG_NAME M_E_CPU1_SA_DQ<10>
J 0
(-3465 5435);
DISPLAY 0.659574 (-3465 5435);
PAINT MONO (-3465 5435);
DISPLAY INVISIBLE (-3465 5435);
FORCEPROP 1 LASTPIN (-3475 5425) BN 10
J 0
(-3487 5433);
DISPLAY 0.489362 (-3487 5433);
PAINT GREEN (-3487 5433);
FORCEPROP 2 LAST CDS_LIB mstr_standard
J 0
(-3425 5425);
DISPLAY 0.723404 (-3425 5425);
PAINT MONO (-3425 5425);
DISPLAY INVISIBLE (-3425 5425);
FORCEPROP 1 LAST BODY_TYPE PLUMBING
J 0
(-3425 5475);
DISPLAY 0.872340 (-3425 5475);
PAINT GREEN (-3425 5475);
DISPLAY INVISIBLE (-3425 5475);
FORCEPROP 1 LAST HDL_TAP TRUE
J 0
(-3100 5300);
DISPLAY 0.872340 (-3100 5300);
DISPLAY INVISIBLE (-3100 5300);
FORCEPROP 1 LAST PATH I172
J 0
(-3427 5425);
DISPLAY 0.872340 (-3427 5425);
PAINT GREEN (-3427 5425);
DISPLAY INVISIBLE (-3427 5425);
FORCEADD TAP..1
(-3425 5375);
FORCEPROP 3 LASTPIN (-3475 5375) SIG_NAME M_E_CPU1_SA_DQ<11>
J 0
(-3465 5385);
DISPLAY 0.659574 (-3465 5385);
PAINT MONO (-3465 5385);
DISPLAY INVISIBLE (-3465 5385);
FORCEPROP 1 LASTPIN (-3475 5375) BN 11
J 0
(-3487 5383);
DISPLAY 0.489362 (-3487 5383);
PAINT GREEN (-3487 5383);
FORCEPROP 2 LAST CDS_LIB mstr_standard
J 0
(-3425 5375);
DISPLAY 0.723404 (-3425 5375);
PAINT MONO (-3425 5375);
DISPLAY INVISIBLE (-3425 5375);
FORCEPROP 1 LAST BODY_TYPE PLUMBING
J 0
(-3425 5425);
DISPLAY 0.872340 (-3425 5425);
PAINT GREEN (-3425 5425);
DISPLAY INVISIBLE (-3425 5425);
FORCEPROP 1 LAST HDL_TAP TRUE
J 0
(-3100 5250);
DISPLAY 0.872340 (-3100 5250);
DISPLAY INVISIBLE (-3100 5250);
FORCEPROP 1 LAST PATH I173
J 0
(-3427 5375);
DISPLAY 0.872340 (-3427 5375);
PAINT GREEN (-3427 5375);
DISPLAY INVISIBLE (-3427 5375);
FORCEADD TAP..1
(-3425 5325);
FORCEPROP 3 LASTPIN (-3475 5325) SIG_NAME M_E_CPU1_SA_DQ<12>
J 0
(-3465 5335);
DISPLAY 0.659574 (-3465 5335);
PAINT MONO (-3465 5335);
DISPLAY INVISIBLE (-3465 5335);
FORCEPROP 1 LASTPIN (-3475 5325) BN 12
J 0
(-3487 5333);
DISPLAY 0.489362 (-3487 5333);
PAINT GREEN (-3487 5333);
FORCEPROP 2 LAST CDS_LIB mstr_standard
J 0
(-3425 5325);
DISPLAY 0.723404 (-3425 5325);
PAINT MONO (-3425 5325);
DISPLAY INVISIBLE (-3425 5325);
FORCEPROP 1 LAST BODY_TYPE PLUMBING
J 0
(-3425 5375);
DISPLAY 0.872340 (-3425 5375);
PAINT GREEN (-3425 5375);
DISPLAY INVISIBLE (-3425 5375);
FORCEPROP 1 LAST HDL_TAP TRUE
J 0
(-3100 5200);
DISPLAY 0.872340 (-3100 5200);
DISPLAY INVISIBLE (-3100 5200);
FORCEPROP 1 LAST PATH I174
J 0
(-3427 5325);
DISPLAY 0.872340 (-3427 5325);
PAINT GREEN (-3427 5325);
DISPLAY INVISIBLE (-3427 5325);
FORCEADD TAP..1
(-3425 5275);
FORCEPROP 3 LASTPIN (-3475 5275) SIG_NAME M_E_CPU1_SA_DQ<13>
J 0
(-3465 5285);
DISPLAY 0.659574 (-3465 5285);
PAINT MONO (-3465 5285);
DISPLAY INVISIBLE (-3465 5285);
FORCEPROP 1 LASTPIN (-3475 5275) BN 13
J 0
(-3487 5283);
DISPLAY 0.489362 (-3487 5283);
PAINT GREEN (-3487 5283);
FORCEPROP 2 LAST CDS_LIB mstr_standard
J 0
(-3425 5275);
DISPLAY 0.723404 (-3425 5275);
PAINT MONO (-3425 5275);
DISPLAY INVISIBLE (-3425 5275);
FORCEPROP 1 LAST BODY_TYPE PLUMBING
J 0
(-3425 5325);
DISPLAY 0.872340 (-3425 5325);
PAINT GREEN (-3425 5325);
DISPLAY INVISIBLE (-3425 5325);
FORCEPROP 1 LAST HDL_TAP TRUE
J 0
(-3100 5150);
DISPLAY 0.872340 (-3100 5150);
DISPLAY INVISIBLE (-3100 5150);
FORCEPROP 1 LAST PATH I175
J 0
(-3427 5275);
DISPLAY 0.872340 (-3427 5275);
PAINT GREEN (-3427 5275);
DISPLAY INVISIBLE (-3427 5275);
FORCEADD TAP..1
(-3425 5225);
FORCEPROP 3 LASTPIN (-3475 5225) SIG_NAME M_E_CPU1_SA_DQ<14>
J 0
(-3465 5235);
DISPLAY 0.659574 (-3465 5235);
PAINT MONO (-3465 5235);
DISPLAY INVISIBLE (-3465 5235);
FORCEPROP 1 LASTPIN (-3475 5225) BN 14
J 0
(-3487 5233);
DISPLAY 0.489362 (-3487 5233);
PAINT GREEN (-3487 5233);
FORCEPROP 2 LAST CDS_LIB mstr_standard
J 0
(-3425 5225);
DISPLAY 0.723404 (-3425 5225);
PAINT MONO (-3425 5225);
DISPLAY INVISIBLE (-3425 5225);
FORCEPROP 1 LAST BODY_TYPE PLUMBING
J 0
(-3425 5275);
DISPLAY 0.872340 (-3425 5275);
PAINT GREEN (-3425 5275);
DISPLAY INVISIBLE (-3425 5275);
FORCEPROP 1 LAST HDL_TAP TRUE
J 0
(-3100 5100);
DISPLAY 0.872340 (-3100 5100);
DISPLAY INVISIBLE (-3100 5100);
FORCEPROP 1 LAST PATH I176
J 0
(-3427 5225);
DISPLAY 0.872340 (-3427 5225);
PAINT GREEN (-3427 5225);
DISPLAY INVISIBLE (-3427 5225);
FORCEADD TAP..1
(-3425 5175);
FORCEPROP 3 LASTPIN (-3475 5175) SIG_NAME M_E_CPU1_SA_DQ<15>
J 0
(-3465 5185);
DISPLAY 0.659574 (-3465 5185);
PAINT MONO (-3465 5185);
DISPLAY INVISIBLE (-3465 5185);
FORCEPROP 1 LASTPIN (-3475 5175) BN 15
J 0
(-3487 5183);
DISPLAY 0.489362 (-3487 5183);
PAINT GREEN (-3487 5183);
FORCEPROP 2 LAST CDS_LIB mstr_standard
J 0
(-3425 5175);
DISPLAY 0.723404 (-3425 5175);
PAINT MONO (-3425 5175);
DISPLAY INVISIBLE (-3425 5175);
FORCEPROP 1 LAST BODY_TYPE PLUMBING
J 0
(-3425 5225);
DISPLAY 0.872340 (-3425 5225);
PAINT GREEN (-3425 5225);
DISPLAY INVISIBLE (-3425 5225);
FORCEPROP 1 LAST HDL_TAP TRUE
J 0
(-3100 5050);
DISPLAY 0.872340 (-3100 5050);
DISPLAY INVISIBLE (-3100 5050);
FORCEPROP 1 LAST PATH I177
J 0
(-3427 5175);
DISPLAY 0.872340 (-3427 5175);
PAINT GREEN (-3427 5175);
DISPLAY INVISIBLE (-3427 5175);
FORCEADD TAP..1
(-3425 5075);
FORCEPROP 3 LASTPIN (-3475 5075) SIG_NAME M_E_CPU1_SA_DQ<16>
J 0
(-3465 5085);
DISPLAY 0.659574 (-3465 5085);
PAINT MONO (-3465 5085);
DISPLAY INVISIBLE (-3465 5085);
FORCEPROP 1 LASTPIN (-3475 5075) BN 16
J 0
(-3487 5083);
DISPLAY 0.489362 (-3487 5083);
PAINT GREEN (-3487 5083);
FORCEPROP 2 LAST CDS_LIB mstr_standard
J 0
(-3425 5075);
DISPLAY 0.723404 (-3425 5075);
PAINT MONO (-3425 5075);
DISPLAY INVISIBLE (-3425 5075);
FORCEPROP 1 LAST BODY_TYPE PLUMBING
J 0
(-3425 5125);
DISPLAY 0.872340 (-3425 5125);
PAINT GREEN (-3425 5125);
DISPLAY INVISIBLE (-3425 5125);
FORCEPROP 1 LAST HDL_TAP TRUE
J 0
(-3100 4950);
DISPLAY 0.872340 (-3100 4950);
DISPLAY INVISIBLE (-3100 4950);
FORCEPROP 1 LAST PATH I178
J 0
(-3427 5075);
DISPLAY 0.872340 (-3427 5075);
PAINT GREEN (-3427 5075);
DISPLAY INVISIBLE (-3427 5075);
FORCEADD TAP..1
(-3425 5025);
FORCEPROP 3 LASTPIN (-3475 5025) SIG_NAME M_E_CPU1_SA_DQ<17>
J 0
(-3465 5035);
DISPLAY 0.659574 (-3465 5035);
PAINT MONO (-3465 5035);
DISPLAY INVISIBLE (-3465 5035);
FORCEPROP 1 LASTPIN (-3475 5025) BN 17
J 0
(-3487 5033);
DISPLAY 0.489362 (-3487 5033);
PAINT GREEN (-3487 5033);
FORCEPROP 2 LAST CDS_LIB mstr_standard
J 0
(-3425 5025);
DISPLAY 0.723404 (-3425 5025);
PAINT MONO (-3425 5025);
DISPLAY INVISIBLE (-3425 5025);
FORCEPROP 1 LAST BODY_TYPE PLUMBING
J 0
(-3425 5075);
DISPLAY 0.872340 (-3425 5075);
PAINT GREEN (-3425 5075);
DISPLAY INVISIBLE (-3425 5075);
FORCEPROP 1 LAST HDL_TAP TRUE
J 0
(-3100 4900);
DISPLAY 0.872340 (-3100 4900);
DISPLAY INVISIBLE (-3100 4900);
FORCEPROP 1 LAST PATH I179
J 0
(-3427 5025);
DISPLAY 0.872340 (-3427 5025);
PAINT GREEN (-3427 5025);
DISPLAY INVISIBLE (-3427 5025);
FORCEADD TAP..1
(-3425 4975);
FORCEPROP 3 LASTPIN (-3475 4975) SIG_NAME M_E_CPU1_SA_DQ<18>
J 0
(-3465 4985);
DISPLAY 0.659574 (-3465 4985);
PAINT MONO (-3465 4985);
DISPLAY INVISIBLE (-3465 4985);
FORCEPROP 1 LASTPIN (-3475 4975) BN 18
J 0
(-3487 4983);
DISPLAY 0.489362 (-3487 4983);
PAINT GREEN (-3487 4983);
FORCEPROP 2 LAST CDS_LIB mstr_standard
J 0
(-3425 4975);
DISPLAY 0.723404 (-3425 4975);
PAINT MONO (-3425 4975);
DISPLAY INVISIBLE (-3425 4975);
FORCEPROP 1 LAST BODY_TYPE PLUMBING
J 0
(-3425 5025);
DISPLAY 0.872340 (-3425 5025);
PAINT GREEN (-3425 5025);
DISPLAY INVISIBLE (-3425 5025);
FORCEPROP 1 LAST HDL_TAP TRUE
J 0
(-3100 4850);
DISPLAY 0.872340 (-3100 4850);
DISPLAY INVISIBLE (-3100 4850);
FORCEPROP 1 LAST PATH I180
J 0
(-3427 4975);
DISPLAY 0.872340 (-3427 4975);
PAINT GREEN (-3427 4975);
DISPLAY INVISIBLE (-3427 4975);
FORCEADD TAP..1
(-3425 4875);
FORCEPROP 3 LASTPIN (-3475 4875) SIG_NAME M_E_CPU1_SA_DQ<20>
J 0
(-3465 4885);
DISPLAY 0.659574 (-3465 4885);
PAINT MONO (-3465 4885);
DISPLAY INVISIBLE (-3465 4885);
FORCEPROP 1 LASTPIN (-3475 4875) BN 20
J 0
(-3487 4883);
DISPLAY 0.489362 (-3487 4883);
PAINT GREEN (-3487 4883);
FORCEPROP 2 LAST CDS_LIB mstr_standard
J 0
(-3425 4875);
DISPLAY 0.723404 (-3425 4875);
PAINT MONO (-3425 4875);
DISPLAY INVISIBLE (-3425 4875);
FORCEPROP 1 LAST BODY_TYPE PLUMBING
J 0
(-3425 4925);
DISPLAY 0.872340 (-3425 4925);
PAINT GREEN (-3425 4925);
DISPLAY INVISIBLE (-3425 4925);
FORCEPROP 1 LAST HDL_TAP TRUE
J 0
(-3100 4750);
DISPLAY 0.872340 (-3100 4750);
DISPLAY INVISIBLE (-3100 4750);
FORCEPROP 1 LAST PATH I181
J 0
(-3427 4875);
DISPLAY 0.872340 (-3427 4875);
PAINT GREEN (-3427 4875);
DISPLAY INVISIBLE (-3427 4875);
FORCEADD TAP..1
(-3425 4925);
FORCEPROP 3 LASTPIN (-3475 4925) SIG_NAME M_E_CPU1_SA_DQ<19>
J 0
(-3465 4935);
DISPLAY 0.659574 (-3465 4935);
PAINT MONO (-3465 4935);
DISPLAY INVISIBLE (-3465 4935);
FORCEPROP 1 LASTPIN (-3475 4925) BN 19
J 0
(-3487 4933);
DISPLAY 0.489362 (-3487 4933);
PAINT GREEN (-3487 4933);
FORCEPROP 2 LAST CDS_LIB mstr_standard
J 0
(-3425 4925);
DISPLAY 0.723404 (-3425 4925);
PAINT MONO (-3425 4925);
DISPLAY INVISIBLE (-3425 4925);
FORCEPROP 1 LAST BODY_TYPE PLUMBING
J 0
(-3425 4975);
DISPLAY 0.872340 (-3425 4975);
PAINT GREEN (-3425 4975);
DISPLAY INVISIBLE (-3425 4975);
FORCEPROP 1 LAST HDL_TAP TRUE
J 0
(-3100 4800);
DISPLAY 0.872340 (-3100 4800);
DISPLAY INVISIBLE (-3100 4800);
FORCEPROP 1 LAST PATH I182
J 0
(-3427 4925);
DISPLAY 0.872340 (-3427 4925);
PAINT GREEN (-3427 4925);
DISPLAY INVISIBLE (-3427 4925);
FORCEADD TAP..1
(-3425 4825);
FORCEPROP 3 LASTPIN (-3475 4825) SIG_NAME M_E_CPU1_SA_DQ<21>
J 0
(-3465 4835);
DISPLAY 0.659574 (-3465 4835);
PAINT MONO (-3465 4835);
DISPLAY INVISIBLE (-3465 4835);
FORCEPROP 1 LASTPIN (-3475 4825) BN 21
J 0
(-3487 4833);
DISPLAY 0.489362 (-3487 4833);
PAINT GREEN (-3487 4833);
FORCEPROP 2 LAST CDS_LIB mstr_standard
J 0
(-3425 4825);
DISPLAY 0.723404 (-3425 4825);
PAINT MONO (-3425 4825);
DISPLAY INVISIBLE (-3425 4825);
FORCEPROP 1 LAST BODY_TYPE PLUMBING
J 0
(-3425 4875);
DISPLAY 0.872340 (-3425 4875);
PAINT GREEN (-3425 4875);
DISPLAY INVISIBLE (-3425 4875);
FORCEPROP 1 LAST HDL_TAP TRUE
J 0
(-3100 4700);
DISPLAY 0.872340 (-3100 4700);
DISPLAY INVISIBLE (-3100 4700);
FORCEPROP 1 LAST PATH I183
J 0
(-3427 4825);
DISPLAY 0.872340 (-3427 4825);
PAINT GREEN (-3427 4825);
DISPLAY INVISIBLE (-3427 4825);
FORCEADD TAP..1
(-3425 4775);
FORCEPROP 3 LASTPIN (-3475 4775) SIG_NAME M_E_CPU1_SA_DQ<22>
J 0
(-3465 4785);
DISPLAY 0.659574 (-3465 4785);
PAINT MONO (-3465 4785);
DISPLAY INVISIBLE (-3465 4785);
FORCEPROP 1 LASTPIN (-3475 4775) BN 22
J 0
(-3487 4783);
DISPLAY 0.489362 (-3487 4783);
PAINT GREEN (-3487 4783);
FORCEPROP 2 LAST CDS_LIB mstr_standard
J 0
(-3425 4775);
DISPLAY 0.723404 (-3425 4775);
PAINT MONO (-3425 4775);
DISPLAY INVISIBLE (-3425 4775);
FORCEPROP 1 LAST BODY_TYPE PLUMBING
J 0
(-3425 4825);
DISPLAY 0.872340 (-3425 4825);
PAINT GREEN (-3425 4825);
DISPLAY INVISIBLE (-3425 4825);
FORCEPROP 1 LAST HDL_TAP TRUE
J 0
(-3100 4650);
DISPLAY 0.872340 (-3100 4650);
DISPLAY INVISIBLE (-3100 4650);
FORCEPROP 1 LAST PATH I184
J 0
(-3427 4775);
DISPLAY 0.872340 (-3427 4775);
PAINT GREEN (-3427 4775);
DISPLAY INVISIBLE (-3427 4775);
FORCEADD TAP..1
(-3425 4725);
FORCEPROP 3 LASTPIN (-3475 4725) SIG_NAME M_E_CPU1_SA_DQ<23>
J 0
(-3465 4735);
DISPLAY 0.659574 (-3465 4735);
PAINT MONO (-3465 4735);
DISPLAY INVISIBLE (-3465 4735);
FORCEPROP 1 LASTPIN (-3475 4725) BN 23
J 0
(-3487 4733);
DISPLAY 0.489362 (-3487 4733);
PAINT GREEN (-3487 4733);
FORCEPROP 2 LAST CDS_LIB mstr_standard
J 0
(-3425 4725);
DISPLAY 0.723404 (-3425 4725);
PAINT MONO (-3425 4725);
DISPLAY INVISIBLE (-3425 4725);
FORCEPROP 1 LAST BODY_TYPE PLUMBING
J 0
(-3425 4775);
DISPLAY 0.872340 (-3425 4775);
PAINT GREEN (-3425 4775);
DISPLAY INVISIBLE (-3425 4775);
FORCEPROP 1 LAST HDL_TAP TRUE
J 0
(-3100 4600);
DISPLAY 0.872340 (-3100 4600);
DISPLAY INVISIBLE (-3100 4600);
FORCEPROP 1 LAST PATH I185
J 0
(-3427 4725);
DISPLAY 0.872340 (-3427 4725);
PAINT GREEN (-3427 4725);
DISPLAY INVISIBLE (-3427 4725);
FORCEADD TAP..1
(-3425 4625);
FORCEPROP 3 LASTPIN (-3475 4625) SIG_NAME M_E_CPU1_SA_DQ<24>
J 0
(-3465 4635);
DISPLAY 0.659574 (-3465 4635);
PAINT MONO (-3465 4635);
DISPLAY INVISIBLE (-3465 4635);
FORCEPROP 1 LASTPIN (-3475 4625) BN 24
J 0
(-3487 4633);
DISPLAY 0.489362 (-3487 4633);
PAINT GREEN (-3487 4633);
FORCEPROP 2 LAST CDS_LIB mstr_standard
J 0
(-3425 4625);
DISPLAY 0.723404 (-3425 4625);
PAINT MONO (-3425 4625);
DISPLAY INVISIBLE (-3425 4625);
FORCEPROP 1 LAST BODY_TYPE PLUMBING
J 0
(-3425 4675);
DISPLAY 0.872340 (-3425 4675);
PAINT GREEN (-3425 4675);
DISPLAY INVISIBLE (-3425 4675);
FORCEPROP 1 LAST HDL_TAP TRUE
J 0
(-3100 4500);
DISPLAY 0.872340 (-3100 4500);
DISPLAY INVISIBLE (-3100 4500);
FORCEPROP 1 LAST PATH I186
J 0
(-3427 4625);
DISPLAY 0.872340 (-3427 4625);
PAINT GREEN (-3427 4625);
DISPLAY INVISIBLE (-3427 4625);
FORCEADD TAP..1
(-3425 4575);
FORCEPROP 3 LASTPIN (-3475 4575) SIG_NAME M_E_CPU1_SA_DQ<25>
J 0
(-3465 4585);
DISPLAY 0.659574 (-3465 4585);
PAINT MONO (-3465 4585);
DISPLAY INVISIBLE (-3465 4585);
FORCEPROP 1 LASTPIN (-3475 4575) BN 25
J 0
(-3487 4583);
DISPLAY 0.489362 (-3487 4583);
PAINT GREEN (-3487 4583);
FORCEPROP 2 LAST CDS_LIB mstr_standard
J 0
(-3425 4575);
DISPLAY 0.723404 (-3425 4575);
PAINT MONO (-3425 4575);
DISPLAY INVISIBLE (-3425 4575);
FORCEPROP 1 LAST BODY_TYPE PLUMBING
J 0
(-3425 4625);
DISPLAY 0.872340 (-3425 4625);
PAINT GREEN (-3425 4625);
DISPLAY INVISIBLE (-3425 4625);
FORCEPROP 1 LAST HDL_TAP TRUE
J 0
(-3100 4450);
DISPLAY 0.872340 (-3100 4450);
DISPLAY INVISIBLE (-3100 4450);
FORCEPROP 1 LAST PATH I187
J 0
(-3427 4575);
DISPLAY 0.872340 (-3427 4575);
PAINT GREEN (-3427 4575);
DISPLAY INVISIBLE (-3427 4575);
FORCEADD TAP..1
(-3425 4525);
FORCEPROP 3 LASTPIN (-3475 4525) SIG_NAME M_E_CPU1_SA_DQ<26>
J 0
(-3465 4535);
DISPLAY 0.659574 (-3465 4535);
PAINT MONO (-3465 4535);
DISPLAY INVISIBLE (-3465 4535);
FORCEPROP 1 LASTPIN (-3475 4525) BN 26
J 0
(-3487 4533);
DISPLAY 0.489362 (-3487 4533);
PAINT GREEN (-3487 4533);
FORCEPROP 2 LAST CDS_LIB mstr_standard
J 0
(-3425 4525);
DISPLAY 0.723404 (-3425 4525);
PAINT MONO (-3425 4525);
DISPLAY INVISIBLE (-3425 4525);
FORCEPROP 1 LAST BODY_TYPE PLUMBING
J 0
(-3425 4575);
DISPLAY 0.872340 (-3425 4575);
PAINT GREEN (-3425 4575);
DISPLAY INVISIBLE (-3425 4575);
FORCEPROP 1 LAST HDL_TAP TRUE
J 0
(-3100 4400);
DISPLAY 0.872340 (-3100 4400);
DISPLAY INVISIBLE (-3100 4400);
FORCEPROP 1 LAST PATH I188
J 0
(-3427 4525);
DISPLAY 0.872340 (-3427 4525);
PAINT GREEN (-3427 4525);
DISPLAY INVISIBLE (-3427 4525);
FORCEADD TAP..1
(-3425 4425);
FORCEPROP 3 LASTPIN (-3475 4425) SIG_NAME M_E_CPU1_SA_DQ<28>
J 0
(-3465 4435);
DISPLAY 0.659574 (-3465 4435);
PAINT MONO (-3465 4435);
DISPLAY INVISIBLE (-3465 4435);
FORCEPROP 1 LASTPIN (-3475 4425) BN 28
J 0
(-3487 4433);
DISPLAY 0.489362 (-3487 4433);
PAINT GREEN (-3487 4433);
FORCEPROP 2 LAST CDS_LIB mstr_standard
J 0
(-3425 4425);
DISPLAY 0.723404 (-3425 4425);
PAINT MONO (-3425 4425);
DISPLAY INVISIBLE (-3425 4425);
FORCEPROP 1 LAST BODY_TYPE PLUMBING
J 0
(-3425 4475);
DISPLAY 0.872340 (-3425 4475);
PAINT GREEN (-3425 4475);
DISPLAY INVISIBLE (-3425 4475);
FORCEPROP 1 LAST HDL_TAP TRUE
J 0
(-3100 4300);
DISPLAY 0.872340 (-3100 4300);
DISPLAY INVISIBLE (-3100 4300);
FORCEPROP 1 LAST PATH I189
J 0
(-3427 4425);
DISPLAY 0.872340 (-3427 4425);
PAINT GREEN (-3427 4425);
DISPLAY INVISIBLE (-3427 4425);
FORCEADD TAP..1
(-3425 4475);
FORCEPROP 3 LASTPIN (-3475 4475) SIG_NAME M_E_CPU1_SA_DQ<27>
J 0
(-3465 4485);
DISPLAY 0.659574 (-3465 4485);
PAINT MONO (-3465 4485);
DISPLAY INVISIBLE (-3465 4485);
FORCEPROP 1 LASTPIN (-3475 4475) BN 27
J 0
(-3487 4483);
DISPLAY 0.489362 (-3487 4483);
PAINT GREEN (-3487 4483);
FORCEPROP 2 LAST CDS_LIB mstr_standard
J 0
(-3425 4475);
DISPLAY 0.723404 (-3425 4475);
PAINT MONO (-3425 4475);
DISPLAY INVISIBLE (-3425 4475);
FORCEPROP 1 LAST BODY_TYPE PLUMBING
J 0
(-3425 4525);
DISPLAY 0.872340 (-3425 4525);
PAINT GREEN (-3425 4525);
DISPLAY INVISIBLE (-3425 4525);
FORCEPROP 1 LAST HDL_TAP TRUE
J 0
(-3100 4350);
DISPLAY 0.872340 (-3100 4350);
DISPLAY INVISIBLE (-3100 4350);
FORCEPROP 1 LAST PATH I190
J 0
(-3427 4475);
DISPLAY 0.872340 (-3427 4475);
PAINT GREEN (-3427 4475);
DISPLAY INVISIBLE (-3427 4475);
FORCEADD TAP..1
(-3425 4375);
FORCEPROP 3 LASTPIN (-3475 4375) SIG_NAME M_E_CPU1_SA_DQ<29>
J 0
(-3465 4385);
DISPLAY 0.659574 (-3465 4385);
PAINT MONO (-3465 4385);
DISPLAY INVISIBLE (-3465 4385);
FORCEPROP 1 LASTPIN (-3475 4375) BN 29
J 0
(-3487 4383);
DISPLAY 0.489362 (-3487 4383);
PAINT GREEN (-3487 4383);
FORCEPROP 2 LAST CDS_LIB mstr_standard
J 0
(-3425 4375);
DISPLAY 0.723404 (-3425 4375);
PAINT MONO (-3425 4375);
DISPLAY INVISIBLE (-3425 4375);
FORCEPROP 1 LAST BODY_TYPE PLUMBING
J 0
(-3425 4425);
DISPLAY 0.872340 (-3425 4425);
PAINT GREEN (-3425 4425);
DISPLAY INVISIBLE (-3425 4425);
FORCEPROP 1 LAST HDL_TAP TRUE
J 0
(-3100 4250);
DISPLAY 0.872340 (-3100 4250);
DISPLAY INVISIBLE (-3100 4250);
FORCEPROP 1 LAST PATH I191
J 0
(-3427 4375);
DISPLAY 0.872340 (-3427 4375);
PAINT GREEN (-3427 4375);
DISPLAY INVISIBLE (-3427 4375);
FORCEADD TAP..1
(-3425 4325);
FORCEPROP 3 LASTPIN (-3475 4325) SIG_NAME M_E_CPU1_SA_DQ<30>
J 0
(-3465 4335);
DISPLAY 0.659574 (-3465 4335);
PAINT MONO (-3465 4335);
DISPLAY INVISIBLE (-3465 4335);
FORCEPROP 1 LASTPIN (-3475 4325) BN 30
J 0
(-3487 4333);
DISPLAY 0.489362 (-3487 4333);
PAINT GREEN (-3487 4333);
FORCEPROP 2 LAST CDS_LIB mstr_standard
J 0
(-3425 4325);
DISPLAY 0.723404 (-3425 4325);
PAINT MONO (-3425 4325);
DISPLAY INVISIBLE (-3425 4325);
FORCEPROP 1 LAST BODY_TYPE PLUMBING
J 0
(-3425 4375);
DISPLAY 0.872340 (-3425 4375);
PAINT GREEN (-3425 4375);
DISPLAY INVISIBLE (-3425 4375);
FORCEPROP 1 LAST HDL_TAP TRUE
J 0
(-3100 4200);
DISPLAY 0.872340 (-3100 4200);
DISPLAY INVISIBLE (-3100 4200);
FORCEPROP 1 LAST PATH I192
J 0
(-3427 4325);
DISPLAY 0.872340 (-3427 4325);
PAINT GREEN (-3427 4325);
DISPLAY INVISIBLE (-3427 4325);
FORCEADD TAP..1
(-3425 4275);
FORCEPROP 3 LASTPIN (-3475 4275) SIG_NAME M_E_CPU1_SA_DQ<31>
J 0
(-3465 4285);
DISPLAY 0.659574 (-3465 4285);
PAINT MONO (-3465 4285);
DISPLAY INVISIBLE (-3465 4285);
FORCEPROP 1 LASTPIN (-3475 4275) BN 31
J 0
(-3487 4283);
DISPLAY 0.489362 (-3487 4283);
PAINT GREEN (-3487 4283);
FORCEPROP 2 LAST CDS_LIB mstr_standard
J 0
(-3425 4275);
DISPLAY 0.723404 (-3425 4275);
PAINT MONO (-3425 4275);
DISPLAY INVISIBLE (-3425 4275);
FORCEPROP 1 LAST BODY_TYPE PLUMBING
J 0
(-3425 4325);
DISPLAY 0.872340 (-3425 4325);
PAINT GREEN (-3425 4325);
DISPLAY INVISIBLE (-3425 4325);
FORCEPROP 1 LAST HDL_TAP TRUE
J 0
(-3100 4150);
DISPLAY 0.872340 (-3100 4150);
DISPLAY INVISIBLE (-3100 4150);
FORCEPROP 1 LAST PATH I193
J 0
(-3427 4275);
DISPLAY 0.872340 (-3427 4275);
PAINT GREEN (-3427 4275);
DISPLAY INVISIBLE (-3427 4275);
FORCEADD TAP..1
(-3425 4175);
FORCEPROP 3 LASTPIN (-3475 4175) SIG_NAME M_E_CPU1_SB_DQ<0>
J 0
(-3465 4185);
DISPLAY 0.659574 (-3465 4185);
PAINT MONO (-3465 4185);
DISPLAY INVISIBLE (-3465 4185);
FORCEPROP 1 LASTPIN (-3475 4175) BN 0
J 0
(-3487 4183);
DISPLAY 0.489362 (-3487 4183);
PAINT GREEN (-3487 4183);
FORCEPROP 2 LAST CDS_LIB mstr_standard
J 0
(-3425 4175);
DISPLAY 0.723404 (-3425 4175);
PAINT MONO (-3425 4175);
DISPLAY INVISIBLE (-3425 4175);
FORCEPROP 1 LAST BODY_TYPE PLUMBING
J 0
(-3425 4225);
DISPLAY 0.872340 (-3425 4225);
PAINT GREEN (-3425 4225);
DISPLAY INVISIBLE (-3425 4225);
FORCEPROP 1 LAST HDL_TAP TRUE
J 0
(-3100 4050);
DISPLAY 0.872340 (-3100 4050);
DISPLAY INVISIBLE (-3100 4050);
FORCEPROP 1 LAST PATH I194
J 0
(-3427 4175);
DISPLAY 0.872340 (-3427 4175);
PAINT GREEN (-3427 4175);
DISPLAY INVISIBLE (-3427 4175);
FORCEADD TAP..1
(-3425 4125);
FORCEPROP 3 LASTPIN (-3475 4125) SIG_NAME M_E_CPU1_SB_DQ<1>
J 0
(-3465 4135);
DISPLAY 0.659574 (-3465 4135);
PAINT MONO (-3465 4135);
DISPLAY INVISIBLE (-3465 4135);
FORCEPROP 1 LASTPIN (-3475 4125) BN 1
J 0
(-3487 4133);
DISPLAY 0.489362 (-3487 4133);
PAINT GREEN (-3487 4133);
FORCEPROP 2 LAST CDS_LIB mstr_standard
J 0
(-3425 4125);
DISPLAY 0.723404 (-3425 4125);
PAINT MONO (-3425 4125);
DISPLAY INVISIBLE (-3425 4125);
FORCEPROP 1 LAST BODY_TYPE PLUMBING
J 0
(-3425 4175);
DISPLAY 0.872340 (-3425 4175);
PAINT GREEN (-3425 4175);
DISPLAY INVISIBLE (-3425 4175);
FORCEPROP 1 LAST HDL_TAP TRUE
J 0
(-3100 4000);
DISPLAY 0.872340 (-3100 4000);
DISPLAY INVISIBLE (-3100 4000);
FORCEPROP 1 LAST PATH I195
J 0
(-3427 4125);
DISPLAY 0.872340 (-3427 4125);
PAINT GREEN (-3427 4125);
DISPLAY INVISIBLE (-3427 4125);
FORCEADD OFFPAGE..6
R 2
(-2825 2425);
FORCEPROP 2 LAST $XR0 102 
J 0
(-2611 2425);
DISPLAY 0.638298 (-2611 2425);
PAINT MONO (-2611 2425);
FORCEPROP 2 LAST CDS_LIB mstr_standard
J 2
(-2825 2425);
DISPLAY 0.723404 (-2825 2425);
PAINT MONO (-2825 2425);
DISPLAY INVISIBLE (-2825 2425);
FORCEPROP 1 LAST OFFPAGE TRUE
J 2
(-3150 2300);
DISPLAY 0.872340 (-3150 2300);
PAINT GREEN (-3150 2300);
DISPLAY INVISIBLE (-3150 2300);
FORCEPROP 1 LAST COMMENT_BODY TRUE
J 2
(-2925 2350);
DISPLAY 0.872340 (-2925 2350);
PAINT GREEN (-2925 2350);
DISPLAY INVISIBLE (-2925 2350);
FORCEPROP 2 LAST PATH I196
J 0
(-2600 2475);
DISPLAY 1.021277 (-2600 2475);
DISPLAY INVISIBLE (-2600 2475);
FORCEADD TAP..1
(-3425 4075);
FORCEPROP 3 LASTPIN (-3475 4075) SIG_NAME M_E_CPU1_SB_DQ<2>
J 0
(-3465 4085);
DISPLAY 0.659574 (-3465 4085);
PAINT MONO (-3465 4085);
DISPLAY INVISIBLE (-3465 4085);
FORCEPROP 1 LASTPIN (-3475 4075) BN 2
J 0
(-3487 4083);
DISPLAY 0.489362 (-3487 4083);
PAINT GREEN (-3487 4083);
FORCEPROP 2 LAST CDS_LIB mstr_standard
J 0
(-3425 4075);
DISPLAY 0.723404 (-3425 4075);
PAINT MONO (-3425 4075);
DISPLAY INVISIBLE (-3425 4075);
FORCEPROP 1 LAST BODY_TYPE PLUMBING
J 0
(-3425 4125);
DISPLAY 0.872340 (-3425 4125);
PAINT GREEN (-3425 4125);
DISPLAY INVISIBLE (-3425 4125);
FORCEPROP 1 LAST HDL_TAP TRUE
J 0
(-3100 3950);
DISPLAY 0.872340 (-3100 3950);
DISPLAY INVISIBLE (-3100 3950);
FORCEPROP 1 LAST PATH I197
J 0
(-3427 4075);
DISPLAY 0.872340 (-3427 4075);
PAINT GREEN (-3427 4075);
DISPLAY INVISIBLE (-3427 4075);
FORCEADD TAP..1
(-3425 3975);
FORCEPROP 3 LASTPIN (-3475 3975) SIG_NAME M_E_CPU1_SB_DQ<4>
J 0
(-3465 3985);
DISPLAY 0.659574 (-3465 3985);
PAINT MONO (-3465 3985);
DISPLAY INVISIBLE (-3465 3985);
FORCEPROP 1 LASTPIN (-3475 3975) BN 4
J 0
(-3487 3983);
DISPLAY 0.489362 (-3487 3983);
PAINT GREEN (-3487 3983);
FORCEPROP 2 LAST CDS_LIB mstr_standard
J 0
(-3425 3975);
DISPLAY 0.723404 (-3425 3975);
PAINT MONO (-3425 3975);
DISPLAY INVISIBLE (-3425 3975);
FORCEPROP 1 LAST BODY_TYPE PLUMBING
J 0
(-3425 4025);
DISPLAY 0.872340 (-3425 4025);
PAINT GREEN (-3425 4025);
DISPLAY INVISIBLE (-3425 4025);
FORCEPROP 1 LAST HDL_TAP TRUE
J 0
(-3100 3850);
DISPLAY 0.872340 (-3100 3850);
DISPLAY INVISIBLE (-3100 3850);
FORCEPROP 1 LAST PATH I198
J 0
(-3427 3975);
DISPLAY 0.872340 (-3427 3975);
PAINT GREEN (-3427 3975);
DISPLAY INVISIBLE (-3427 3975);
FORCEADD TAP..1
(-3425 4025);
FORCEPROP 3 LASTPIN (-3475 4025) SIG_NAME M_E_CPU1_SB_DQ<3>
J 0
(-3465 4035);
DISPLAY 0.659574 (-3465 4035);
PAINT MONO (-3465 4035);
DISPLAY INVISIBLE (-3465 4035);
FORCEPROP 1 LASTPIN (-3475 4025) BN 3
J 0
(-3487 4033);
DISPLAY 0.489362 (-3487 4033);
PAINT GREEN (-3487 4033);
FORCEPROP 2 LAST CDS_LIB mstr_standard
J 0
(-3425 4025);
DISPLAY 0.723404 (-3425 4025);
PAINT MONO (-3425 4025);
DISPLAY INVISIBLE (-3425 4025);
FORCEPROP 1 LAST BODY_TYPE PLUMBING
J 0
(-3425 4075);
DISPLAY 0.872340 (-3425 4075);
PAINT GREEN (-3425 4075);
DISPLAY INVISIBLE (-3425 4075);
FORCEPROP 1 LAST HDL_TAP TRUE
J 0
(-3100 3900);
DISPLAY 0.872340 (-3100 3900);
DISPLAY INVISIBLE (-3100 3900);
FORCEPROP 1 LAST PATH I199
J 0
(-3427 4025);
DISPLAY 0.872340 (-3427 4025);
PAINT GREEN (-3427 4025);
DISPLAY INVISIBLE (-3427 4025);
FORCEADD TAP..1
(-3425 3925);
FORCEPROP 3 LASTPIN (-3475 3925) SIG_NAME M_E_CPU1_SB_DQ<5>
J 0
(-3465 3935);
DISPLAY 0.659574 (-3465 3935);
PAINT MONO (-3465 3935);
DISPLAY INVISIBLE (-3465 3935);
FORCEPROP 1 LASTPIN (-3475 3925) BN 5
J 0
(-3487 3933);
DISPLAY 0.489362 (-3487 3933);
PAINT GREEN (-3487 3933);
FORCEPROP 2 LAST CDS_LIB mstr_standard
J 0
(-3425 3925);
DISPLAY 0.723404 (-3425 3925);
PAINT MONO (-3425 3925);
DISPLAY INVISIBLE (-3425 3925);
FORCEPROP 1 LAST BODY_TYPE PLUMBING
J 0
(-3425 3975);
DISPLAY 0.872340 (-3425 3975);
PAINT GREEN (-3425 3975);
DISPLAY INVISIBLE (-3425 3975);
FORCEPROP 1 LAST HDL_TAP TRUE
J 0
(-3100 3800);
DISPLAY 0.872340 (-3100 3800);
DISPLAY INVISIBLE (-3100 3800);
FORCEPROP 1 LAST PATH I200
J 0
(-3427 3925);
DISPLAY 0.872340 (-3427 3925);
PAINT GREEN (-3427 3925);
DISPLAY INVISIBLE (-3427 3925);
FORCEADD TAP..1
(-3425 3875);
FORCEPROP 3 LASTPIN (-3475 3875) SIG_NAME M_E_CPU1_SB_DQ<6>
J 0
(-3465 3885);
DISPLAY 0.659574 (-3465 3885);
PAINT MONO (-3465 3885);
DISPLAY INVISIBLE (-3465 3885);
FORCEPROP 1 LASTPIN (-3475 3875) BN 6
J 0
(-3487 3883);
DISPLAY 0.489362 (-3487 3883);
PAINT GREEN (-3487 3883);
FORCEPROP 2 LAST CDS_LIB mstr_standard
J 0
(-3425 3875);
DISPLAY 0.723404 (-3425 3875);
PAINT MONO (-3425 3875);
DISPLAY INVISIBLE (-3425 3875);
FORCEPROP 1 LAST BODY_TYPE PLUMBING
J 0
(-3425 3925);
DISPLAY 0.872340 (-3425 3925);
PAINT GREEN (-3425 3925);
DISPLAY INVISIBLE (-3425 3925);
FORCEPROP 1 LAST HDL_TAP TRUE
J 0
(-3100 3750);
DISPLAY 0.872340 (-3100 3750);
DISPLAY INVISIBLE (-3100 3750);
FORCEPROP 1 LAST PATH I201
J 0
(-3427 3875);
DISPLAY 0.872340 (-3427 3875);
PAINT GREEN (-3427 3875);
DISPLAY INVISIBLE (-3427 3875);
FORCEADD TAP..1
(-3425 3825);
FORCEPROP 3 LASTPIN (-3475 3825) SIG_NAME M_E_CPU1_SB_DQ<7>
J 0
(-3465 3835);
DISPLAY 0.659574 (-3465 3835);
PAINT MONO (-3465 3835);
DISPLAY INVISIBLE (-3465 3835);
FORCEPROP 1 LASTPIN (-3475 3825) BN 7
J 0
(-3487 3833);
DISPLAY 0.489362 (-3487 3833);
PAINT GREEN (-3487 3833);
FORCEPROP 2 LAST CDS_LIB mstr_standard
J 0
(-3425 3825);
DISPLAY 0.723404 (-3425 3825);
PAINT MONO (-3425 3825);
DISPLAY INVISIBLE (-3425 3825);
FORCEPROP 1 LAST BODY_TYPE PLUMBING
J 0
(-3425 3875);
DISPLAY 0.872340 (-3425 3875);
PAINT GREEN (-3425 3875);
DISPLAY INVISIBLE (-3425 3875);
FORCEPROP 1 LAST HDL_TAP TRUE
J 0
(-3100 3700);
DISPLAY 0.872340 (-3100 3700);
DISPLAY INVISIBLE (-3100 3700);
FORCEPROP 1 LAST PATH I202
J 0
(-3427 3825);
DISPLAY 0.872340 (-3427 3825);
PAINT GREEN (-3427 3825);
DISPLAY INVISIBLE (-3427 3825);
FORCEADD TAP..1
(-3425 3725);
FORCEPROP 3 LASTPIN (-3475 3725) SIG_NAME M_E_CPU1_SB_DQ<8>
J 0
(-3465 3735);
DISPLAY 0.659574 (-3465 3735);
PAINT MONO (-3465 3735);
DISPLAY INVISIBLE (-3465 3735);
FORCEPROP 1 LASTPIN (-3475 3725) BN 8
J 0
(-3487 3733);
DISPLAY 0.489362 (-3487 3733);
PAINT GREEN (-3487 3733);
FORCEPROP 2 LAST CDS_LIB mstr_standard
J 0
(-3425 3725);
DISPLAY 0.723404 (-3425 3725);
PAINT MONO (-3425 3725);
DISPLAY INVISIBLE (-3425 3725);
FORCEPROP 1 LAST BODY_TYPE PLUMBING
J 0
(-3425 3775);
DISPLAY 0.872340 (-3425 3775);
PAINT GREEN (-3425 3775);
DISPLAY INVISIBLE (-3425 3775);
FORCEPROP 1 LAST HDL_TAP TRUE
J 0
(-3100 3600);
DISPLAY 0.872340 (-3100 3600);
DISPLAY INVISIBLE (-3100 3600);
FORCEPROP 1 LAST PATH I203
J 0
(-3427 3725);
DISPLAY 0.872340 (-3427 3725);
PAINT GREEN (-3427 3725);
DISPLAY INVISIBLE (-3427 3725);
FORCEADD TAP..1
(-3425 3675);
FORCEPROP 3 LASTPIN (-3475 3675) SIG_NAME M_E_CPU1_SB_DQ<9>
J 0
(-3465 3685);
DISPLAY 0.659574 (-3465 3685);
PAINT MONO (-3465 3685);
DISPLAY INVISIBLE (-3465 3685);
FORCEPROP 1 LASTPIN (-3475 3675) BN 9
J 0
(-3487 3683);
DISPLAY 0.489362 (-3487 3683);
PAINT GREEN (-3487 3683);
FORCEPROP 2 LAST CDS_LIB mstr_standard
J 0
(-3425 3675);
DISPLAY 0.723404 (-3425 3675);
PAINT MONO (-3425 3675);
DISPLAY INVISIBLE (-3425 3675);
FORCEPROP 1 LAST BODY_TYPE PLUMBING
J 0
(-3425 3725);
DISPLAY 0.872340 (-3425 3725);
PAINT GREEN (-3425 3725);
DISPLAY INVISIBLE (-3425 3725);
FORCEPROP 1 LAST HDL_TAP TRUE
J 0
(-3100 3550);
DISPLAY 0.872340 (-3100 3550);
DISPLAY INVISIBLE (-3100 3550);
FORCEPROP 1 LAST PATH I204
J 0
(-3427 3675);
DISPLAY 0.872340 (-3427 3675);
PAINT GREEN (-3427 3675);
DISPLAY INVISIBLE (-3427 3675);
FORCEADD TAP..1
(-3425 3625);
FORCEPROP 3 LASTPIN (-3475 3625) SIG_NAME M_E_CPU1_SB_DQ<10>
J 0
(-3465 3635);
DISPLAY 0.659574 (-3465 3635);
PAINT MONO (-3465 3635);
DISPLAY INVISIBLE (-3465 3635);
FORCEPROP 1 LASTPIN (-3475 3625) BN 10
J 0
(-3487 3633);
DISPLAY 0.489362 (-3487 3633);
PAINT GREEN (-3487 3633);
FORCEPROP 2 LAST CDS_LIB mstr_standard
J 0
(-3425 3625);
DISPLAY 0.723404 (-3425 3625);
PAINT MONO (-3425 3625);
DISPLAY INVISIBLE (-3425 3625);
FORCEPROP 1 LAST BODY_TYPE PLUMBING
J 0
(-3425 3675);
DISPLAY 0.872340 (-3425 3675);
PAINT GREEN (-3425 3675);
DISPLAY INVISIBLE (-3425 3675);
FORCEPROP 1 LAST HDL_TAP TRUE
J 0
(-3100 3500);
DISPLAY 0.872340 (-3100 3500);
DISPLAY INVISIBLE (-3100 3500);
FORCEPROP 1 LAST PATH I205
J 0
(-3427 3625);
DISPLAY 0.872340 (-3427 3625);
PAINT GREEN (-3427 3625);
DISPLAY INVISIBLE (-3427 3625);
FORCEADD TAP..1
(-3425 3575);
FORCEPROP 3 LASTPIN (-3475 3575) SIG_NAME M_E_CPU1_SB_DQ<11>
J 0
(-3465 3585);
DISPLAY 0.659574 (-3465 3585);
PAINT MONO (-3465 3585);
DISPLAY INVISIBLE (-3465 3585);
FORCEPROP 1 LASTPIN (-3475 3575) BN 11
J 0
(-3487 3583);
DISPLAY 0.489362 (-3487 3583);
PAINT GREEN (-3487 3583);
FORCEPROP 2 LAST CDS_LIB mstr_standard
J 0
(-3425 3575);
DISPLAY 0.723404 (-3425 3575);
PAINT MONO (-3425 3575);
DISPLAY INVISIBLE (-3425 3575);
FORCEPROP 1 LAST BODY_TYPE PLUMBING
J 0
(-3425 3625);
DISPLAY 0.872340 (-3425 3625);
PAINT GREEN (-3425 3625);
DISPLAY INVISIBLE (-3425 3625);
FORCEPROP 1 LAST HDL_TAP TRUE
J 0
(-3100 3450);
DISPLAY 0.872340 (-3100 3450);
DISPLAY INVISIBLE (-3100 3450);
FORCEPROP 1 LAST PATH I206
J 0
(-3427 3575);
DISPLAY 0.872340 (-3427 3575);
PAINT GREEN (-3427 3575);
DISPLAY INVISIBLE (-3427 3575);
FORCEADD TAP..1
(-3425 3525);
FORCEPROP 3 LASTPIN (-3475 3525) SIG_NAME M_E_CPU1_SB_DQ<12>
J 0
(-3465 3535);
DISPLAY 0.659574 (-3465 3535);
PAINT MONO (-3465 3535);
DISPLAY INVISIBLE (-3465 3535);
FORCEPROP 1 LASTPIN (-3475 3525) BN 12
J 0
(-3487 3533);
DISPLAY 0.489362 (-3487 3533);
PAINT GREEN (-3487 3533);
FORCEPROP 2 LAST CDS_LIB mstr_standard
J 0
(-3425 3525);
DISPLAY 0.723404 (-3425 3525);
PAINT MONO (-3425 3525);
DISPLAY INVISIBLE (-3425 3525);
FORCEPROP 1 LAST BODY_TYPE PLUMBING
J 0
(-3425 3575);
DISPLAY 0.872340 (-3425 3575);
PAINT GREEN (-3425 3575);
DISPLAY INVISIBLE (-3425 3575);
FORCEPROP 1 LAST HDL_TAP TRUE
J 0
(-3100 3400);
DISPLAY 0.872340 (-3100 3400);
DISPLAY INVISIBLE (-3100 3400);
FORCEPROP 1 LAST PATH I207
J 0
(-3427 3525);
DISPLAY 0.872340 (-3427 3525);
PAINT GREEN (-3427 3525);
DISPLAY INVISIBLE (-3427 3525);
FORCEADD TAP..1
(-3425 3475);
FORCEPROP 3 LASTPIN (-3475 3475) SIG_NAME M_E_CPU1_SB_DQ<13>
J 0
(-3465 3485);
DISPLAY 0.659574 (-3465 3485);
PAINT MONO (-3465 3485);
DISPLAY INVISIBLE (-3465 3485);
FORCEPROP 1 LASTPIN (-3475 3475) BN 13
J 0
(-3487 3483);
DISPLAY 0.489362 (-3487 3483);
PAINT GREEN (-3487 3483);
FORCEPROP 2 LAST CDS_LIB mstr_standard
J 0
(-3425 3475);
DISPLAY 0.723404 (-3425 3475);
PAINT MONO (-3425 3475);
DISPLAY INVISIBLE (-3425 3475);
FORCEPROP 1 LAST BODY_TYPE PLUMBING
J 0
(-3425 3525);
DISPLAY 0.872340 (-3425 3525);
PAINT GREEN (-3425 3525);
DISPLAY INVISIBLE (-3425 3525);
FORCEPROP 1 LAST HDL_TAP TRUE
J 0
(-3100 3350);
DISPLAY 0.872340 (-3100 3350);
DISPLAY INVISIBLE (-3100 3350);
FORCEPROP 1 LAST PATH I208
J 0
(-3427 3475);
DISPLAY 0.872340 (-3427 3475);
PAINT GREEN (-3427 3475);
DISPLAY INVISIBLE (-3427 3475);
FORCEADD TAP..1
(-3425 3425);
FORCEPROP 3 LASTPIN (-3475 3425) SIG_NAME M_E_CPU1_SB_DQ<14>
J 0
(-3465 3435);
DISPLAY 0.659574 (-3465 3435);
PAINT MONO (-3465 3435);
DISPLAY INVISIBLE (-3465 3435);
FORCEPROP 1 LASTPIN (-3475 3425) BN 14
J 0
(-3487 3433);
DISPLAY 0.489362 (-3487 3433);
PAINT GREEN (-3487 3433);
FORCEPROP 2 LAST CDS_LIB mstr_standard
J 0
(-3425 3425);
DISPLAY 0.723404 (-3425 3425);
PAINT MONO (-3425 3425);
DISPLAY INVISIBLE (-3425 3425);
FORCEPROP 1 LAST BODY_TYPE PLUMBING
J 0
(-3425 3475);
DISPLAY 0.872340 (-3425 3475);
PAINT GREEN (-3425 3475);
DISPLAY INVISIBLE (-3425 3475);
FORCEPROP 1 LAST HDL_TAP TRUE
J 0
(-3100 3300);
DISPLAY 0.872340 (-3100 3300);
DISPLAY INVISIBLE (-3100 3300);
FORCEPROP 1 LAST PATH I209
J 0
(-3427 3425);
DISPLAY 0.872340 (-3427 3425);
PAINT GREEN (-3427 3425);
DISPLAY INVISIBLE (-3427 3425);
FORCEADD TAP..1
(-3425 3375);
FORCEPROP 3 LASTPIN (-3475 3375) SIG_NAME M_E_CPU1_SB_DQ<15>
J 0
(-3465 3385);
DISPLAY 0.659574 (-3465 3385);
PAINT MONO (-3465 3385);
DISPLAY INVISIBLE (-3465 3385);
FORCEPROP 1 LASTPIN (-3475 3375) BN 15
J 0
(-3487 3383);
DISPLAY 0.489362 (-3487 3383);
PAINT GREEN (-3487 3383);
FORCEPROP 2 LAST CDS_LIB mstr_standard
J 0
(-3425 3375);
DISPLAY 0.723404 (-3425 3375);
PAINT MONO (-3425 3375);
DISPLAY INVISIBLE (-3425 3375);
FORCEPROP 1 LAST BODY_TYPE PLUMBING
J 0
(-3425 3425);
DISPLAY 0.872340 (-3425 3425);
PAINT GREEN (-3425 3425);
DISPLAY INVISIBLE (-3425 3425);
FORCEPROP 1 LAST HDL_TAP TRUE
J 0
(-3100 3250);
DISPLAY 0.872340 (-3100 3250);
DISPLAY INVISIBLE (-3100 3250);
FORCEPROP 1 LAST PATH I210
J 0
(-3427 3375);
DISPLAY 0.872340 (-3427 3375);
PAINT GREEN (-3427 3375);
DISPLAY INVISIBLE (-3427 3375);
FORCEADD TAP..1
(-3425 3275);
FORCEPROP 3 LASTPIN (-3475 3275) SIG_NAME M_E_CPU1_SB_DQ<16>
J 0
(-3465 3285);
DISPLAY 0.659574 (-3465 3285);
PAINT MONO (-3465 3285);
DISPLAY INVISIBLE (-3465 3285);
FORCEPROP 1 LASTPIN (-3475 3275) BN 16
J 0
(-3487 3283);
DISPLAY 0.489362 (-3487 3283);
PAINT GREEN (-3487 3283);
FORCEPROP 2 LAST CDS_LIB mstr_standard
J 0
(-3425 3275);
DISPLAY 0.723404 (-3425 3275);
PAINT MONO (-3425 3275);
DISPLAY INVISIBLE (-3425 3275);
FORCEPROP 1 LAST BODY_TYPE PLUMBING
J 0
(-3425 3325);
DISPLAY 0.872340 (-3425 3325);
PAINT GREEN (-3425 3325);
DISPLAY INVISIBLE (-3425 3325);
FORCEPROP 1 LAST HDL_TAP TRUE
J 0
(-3100 3150);
DISPLAY 0.872340 (-3100 3150);
DISPLAY INVISIBLE (-3100 3150);
FORCEPROP 1 LAST PATH I211
J 0
(-3427 3275);
DISPLAY 0.872340 (-3427 3275);
PAINT GREEN (-3427 3275);
DISPLAY INVISIBLE (-3427 3275);
FORCEADD TAP..1
(-3425 3225);
FORCEPROP 3 LASTPIN (-3475 3225) SIG_NAME M_E_CPU1_SB_DQ<17>
J 0
(-3465 3235);
DISPLAY 0.659574 (-3465 3235);
PAINT MONO (-3465 3235);
DISPLAY INVISIBLE (-3465 3235);
FORCEPROP 1 LASTPIN (-3475 3225) BN 17
J 0
(-3487 3233);
DISPLAY 0.489362 (-3487 3233);
PAINT GREEN (-3487 3233);
FORCEPROP 2 LAST CDS_LIB mstr_standard
J 0
(-3425 3225);
DISPLAY 0.723404 (-3425 3225);
PAINT MONO (-3425 3225);
DISPLAY INVISIBLE (-3425 3225);
FORCEPROP 1 LAST BODY_TYPE PLUMBING
J 0
(-3425 3275);
DISPLAY 0.872340 (-3425 3275);
PAINT GREEN (-3425 3275);
DISPLAY INVISIBLE (-3425 3275);
FORCEPROP 1 LAST HDL_TAP TRUE
J 0
(-3100 3100);
DISPLAY 0.872340 (-3100 3100);
DISPLAY INVISIBLE (-3100 3100);
FORCEPROP 1 LAST PATH I212
J 0
(-3427 3225);
DISPLAY 0.872340 (-3427 3225);
PAINT GREEN (-3427 3225);
DISPLAY INVISIBLE (-3427 3225);
FORCEADD TAP..1
(-3425 3175);
FORCEPROP 3 LASTPIN (-3475 3175) SIG_NAME M_E_CPU1_SB_DQ<18>
J 0
(-3465 3185);
DISPLAY 0.659574 (-3465 3185);
PAINT MONO (-3465 3185);
DISPLAY INVISIBLE (-3465 3185);
FORCEPROP 1 LASTPIN (-3475 3175) BN 18
J 0
(-3487 3183);
DISPLAY 0.489362 (-3487 3183);
PAINT GREEN (-3487 3183);
FORCEPROP 2 LAST CDS_LIB mstr_standard
J 0
(-3425 3175);
DISPLAY 0.723404 (-3425 3175);
PAINT MONO (-3425 3175);
DISPLAY INVISIBLE (-3425 3175);
FORCEPROP 1 LAST BODY_TYPE PLUMBING
J 0
(-3425 3225);
DISPLAY 0.872340 (-3425 3225);
PAINT GREEN (-3425 3225);
DISPLAY INVISIBLE (-3425 3225);
FORCEPROP 1 LAST HDL_TAP TRUE
J 0
(-3100 3050);
DISPLAY 0.872340 (-3100 3050);
DISPLAY INVISIBLE (-3100 3050);
FORCEPROP 1 LAST PATH I213
J 0
(-3427 3175);
DISPLAY 0.872340 (-3427 3175);
PAINT GREEN (-3427 3175);
DISPLAY INVISIBLE (-3427 3175);
FORCEADD TAP..1
(-3425 3075);
FORCEPROP 3 LASTPIN (-3475 3075) SIG_NAME M_E_CPU1_SB_DQ<20>
J 0
(-3465 3085);
DISPLAY 0.659574 (-3465 3085);
PAINT MONO (-3465 3085);
DISPLAY INVISIBLE (-3465 3085);
FORCEPROP 1 LASTPIN (-3475 3075) BN 20
J 0
(-3487 3083);
DISPLAY 0.489362 (-3487 3083);
PAINT GREEN (-3487 3083);
FORCEPROP 2 LAST CDS_LIB mstr_standard
J 0
(-3425 3075);
DISPLAY 0.723404 (-3425 3075);
PAINT MONO (-3425 3075);
DISPLAY INVISIBLE (-3425 3075);
FORCEPROP 1 LAST BODY_TYPE PLUMBING
J 0
(-3425 3125);
DISPLAY 0.872340 (-3425 3125);
PAINT GREEN (-3425 3125);
DISPLAY INVISIBLE (-3425 3125);
FORCEPROP 1 LAST HDL_TAP TRUE
J 0
(-3100 2950);
DISPLAY 0.872340 (-3100 2950);
DISPLAY INVISIBLE (-3100 2950);
FORCEPROP 1 LAST PATH I214
J 0
(-3427 3075);
DISPLAY 0.872340 (-3427 3075);
PAINT GREEN (-3427 3075);
DISPLAY INVISIBLE (-3427 3075);
FORCEADD TAP..1
(-3425 3125);
FORCEPROP 3 LASTPIN (-3475 3125) SIG_NAME M_E_CPU1_SB_DQ<19>
J 0
(-3465 3135);
DISPLAY 0.659574 (-3465 3135);
PAINT MONO (-3465 3135);
DISPLAY INVISIBLE (-3465 3135);
FORCEPROP 1 LASTPIN (-3475 3125) BN 19
J 0
(-3487 3133);
DISPLAY 0.489362 (-3487 3133);
PAINT GREEN (-3487 3133);
FORCEPROP 2 LAST CDS_LIB mstr_standard
J 0
(-3425 3125);
DISPLAY 0.723404 (-3425 3125);
PAINT MONO (-3425 3125);
DISPLAY INVISIBLE (-3425 3125);
FORCEPROP 1 LAST BODY_TYPE PLUMBING
J 0
(-3425 3175);
DISPLAY 0.872340 (-3425 3175);
PAINT GREEN (-3425 3175);
DISPLAY INVISIBLE (-3425 3175);
FORCEPROP 1 LAST HDL_TAP TRUE
J 0
(-3100 3000);
DISPLAY 0.872340 (-3100 3000);
DISPLAY INVISIBLE (-3100 3000);
FORCEPROP 1 LAST PATH I215
J 0
(-3427 3125);
DISPLAY 0.872340 (-3427 3125);
PAINT GREEN (-3427 3125);
DISPLAY INVISIBLE (-3427 3125);
FORCEADD TAP..1
(-3425 2975);
FORCEPROP 3 LASTPIN (-3475 2975) SIG_NAME M_E_CPU1_SB_DQ<22>
J 0
(-3465 2985);
DISPLAY 0.659574 (-3465 2985);
PAINT MONO (-3465 2985);
DISPLAY INVISIBLE (-3465 2985);
FORCEPROP 1 LASTPIN (-3475 2975) BN 22
J 0
(-3487 2983);
DISPLAY 0.489362 (-3487 2983);
PAINT GREEN (-3487 2983);
FORCEPROP 2 LAST CDS_LIB mstr_standard
J 0
(-3425 2975);
DISPLAY 0.723404 (-3425 2975);
PAINT MONO (-3425 2975);
DISPLAY INVISIBLE (-3425 2975);
FORCEPROP 1 LAST BODY_TYPE PLUMBING
J 0
(-3425 3025);
DISPLAY 0.872340 (-3425 3025);
PAINT GREEN (-3425 3025);
DISPLAY INVISIBLE (-3425 3025);
FORCEPROP 1 LAST HDL_TAP TRUE
J 0
(-3100 2850);
DISPLAY 0.872340 (-3100 2850);
DISPLAY INVISIBLE (-3100 2850);
FORCEPROP 1 LAST PATH I216
J 0
(-3427 2975);
DISPLAY 0.872340 (-3427 2975);
PAINT GREEN (-3427 2975);
DISPLAY INVISIBLE (-3427 2975);
FORCEADD TAP..1
(-3425 3025);
FORCEPROP 3 LASTPIN (-3475 3025) SIG_NAME M_E_CPU1_SB_DQ<21>
J 0
(-3465 3035);
DISPLAY 0.659574 (-3465 3035);
PAINT MONO (-3465 3035);
DISPLAY INVISIBLE (-3465 3035);
FORCEPROP 1 LASTPIN (-3475 3025) BN 21
J 0
(-3487 3033);
DISPLAY 0.489362 (-3487 3033);
PAINT GREEN (-3487 3033);
FORCEPROP 2 LAST CDS_LIB mstr_standard
J 0
(-3425 3025);
DISPLAY 0.723404 (-3425 3025);
PAINT MONO (-3425 3025);
DISPLAY INVISIBLE (-3425 3025);
FORCEPROP 1 LAST BODY_TYPE PLUMBING
J 0
(-3425 3075);
DISPLAY 0.872340 (-3425 3075);
PAINT GREEN (-3425 3075);
DISPLAY INVISIBLE (-3425 3075);
FORCEPROP 1 LAST HDL_TAP TRUE
J 0
(-3100 2900);
DISPLAY 0.872340 (-3100 2900);
DISPLAY INVISIBLE (-3100 2900);
FORCEPROP 1 LAST PATH I217
J 0
(-3427 3025);
DISPLAY 0.872340 (-3427 3025);
PAINT GREEN (-3427 3025);
DISPLAY INVISIBLE (-3427 3025);
FORCEADD TAP..1
(-3425 2825);
FORCEPROP 3 LASTPIN (-3475 2825) SIG_NAME M_E_CPU1_SB_DQ<24>
J 0
(-3465 2835);
DISPLAY 0.659574 (-3465 2835);
PAINT MONO (-3465 2835);
DISPLAY INVISIBLE (-3465 2835);
FORCEPROP 1 LASTPIN (-3475 2825) BN 24
J 0
(-3487 2833);
DISPLAY 0.489362 (-3487 2833);
PAINT GREEN (-3487 2833);
FORCEPROP 2 LAST CDS_LIB mstr_standard
J 0
(-3425 2825);
DISPLAY 0.723404 (-3425 2825);
PAINT MONO (-3425 2825);
DISPLAY INVISIBLE (-3425 2825);
FORCEPROP 1 LAST BODY_TYPE PLUMBING
J 0
(-3425 2875);
DISPLAY 0.872340 (-3425 2875);
PAINT GREEN (-3425 2875);
DISPLAY INVISIBLE (-3425 2875);
FORCEPROP 1 LAST HDL_TAP TRUE
J 0
(-3100 2700);
DISPLAY 0.872340 (-3100 2700);
DISPLAY INVISIBLE (-3100 2700);
FORCEPROP 1 LAST PATH I218
J 0
(-3427 2825);
DISPLAY 0.872340 (-3427 2825);
PAINT GREEN (-3427 2825);
DISPLAY INVISIBLE (-3427 2825);
FORCEADD TAP..1
(-3425 2925);
FORCEPROP 3 LASTPIN (-3475 2925) SIG_NAME M_E_CPU1_SB_DQ<23>
J 0
(-3465 2935);
DISPLAY 0.659574 (-3465 2935);
PAINT MONO (-3465 2935);
DISPLAY INVISIBLE (-3465 2935);
FORCEPROP 1 LASTPIN (-3475 2925) BN 23
J 0
(-3487 2933);
DISPLAY 0.489362 (-3487 2933);
PAINT GREEN (-3487 2933);
FORCEPROP 2 LAST CDS_LIB mstr_standard
J 0
(-3425 2925);
DISPLAY 0.723404 (-3425 2925);
PAINT MONO (-3425 2925);
DISPLAY INVISIBLE (-3425 2925);
FORCEPROP 1 LAST BODY_TYPE PLUMBING
J 0
(-3425 2975);
DISPLAY 0.872340 (-3425 2975);
PAINT GREEN (-3425 2975);
DISPLAY INVISIBLE (-3425 2975);
FORCEPROP 1 LAST HDL_TAP TRUE
J 0
(-3100 2800);
DISPLAY 0.872340 (-3100 2800);
DISPLAY INVISIBLE (-3100 2800);
FORCEPROP 1 LAST PATH I219
J 0
(-3427 2925);
DISPLAY 0.872340 (-3427 2925);
PAINT GREEN (-3427 2925);
DISPLAY INVISIBLE (-3427 2925);
FORCEADD TAP..1
(-3425 2775);
FORCEPROP 3 LASTPIN (-3475 2775) SIG_NAME M_E_CPU1_SB_DQ<25>
J 0
(-3465 2785);
DISPLAY 0.659574 (-3465 2785);
PAINT MONO (-3465 2785);
DISPLAY INVISIBLE (-3465 2785);
FORCEPROP 1 LASTPIN (-3475 2775) BN 25
J 0
(-3487 2783);
DISPLAY 0.489362 (-3487 2783);
PAINT GREEN (-3487 2783);
FORCEPROP 2 LAST CDS_LIB mstr_standard
J 0
(-3425 2775);
DISPLAY 0.723404 (-3425 2775);
PAINT MONO (-3425 2775);
DISPLAY INVISIBLE (-3425 2775);
FORCEPROP 1 LAST BODY_TYPE PLUMBING
J 0
(-3425 2825);
DISPLAY 0.872340 (-3425 2825);
PAINT GREEN (-3425 2825);
DISPLAY INVISIBLE (-3425 2825);
FORCEPROP 1 LAST HDL_TAP TRUE
J 0
(-3100 2650);
DISPLAY 0.872340 (-3100 2650);
DISPLAY INVISIBLE (-3100 2650);
FORCEPROP 1 LAST PATH I220
J 0
(-3427 2775);
DISPLAY 0.872340 (-3427 2775);
PAINT GREEN (-3427 2775);
DISPLAY INVISIBLE (-3427 2775);
FORCEADD TAP..1
(-3425 2725);
FORCEPROP 3 LASTPIN (-3475 2725) SIG_NAME M_E_CPU1_SB_DQ<26>
J 0
(-3465 2735);
DISPLAY 0.659574 (-3465 2735);
PAINT MONO (-3465 2735);
DISPLAY INVISIBLE (-3465 2735);
FORCEPROP 1 LASTPIN (-3475 2725) BN 26
J 0
(-3487 2733);
DISPLAY 0.489362 (-3487 2733);
PAINT GREEN (-3487 2733);
FORCEPROP 2 LAST CDS_LIB mstr_standard
J 0
(-3425 2725);
DISPLAY 0.723404 (-3425 2725);
PAINT MONO (-3425 2725);
DISPLAY INVISIBLE (-3425 2725);
FORCEPROP 1 LAST BODY_TYPE PLUMBING
J 0
(-3425 2775);
DISPLAY 0.872340 (-3425 2775);
PAINT GREEN (-3425 2775);
DISPLAY INVISIBLE (-3425 2775);
FORCEPROP 1 LAST HDL_TAP TRUE
J 0
(-3100 2600);
DISPLAY 0.872340 (-3100 2600);
DISPLAY INVISIBLE (-3100 2600);
FORCEPROP 1 LAST PATH I221
J 0
(-3427 2725);
DISPLAY 0.872340 (-3427 2725);
PAINT GREEN (-3427 2725);
DISPLAY INVISIBLE (-3427 2725);
FORCEADD TAP..1
(-3425 2625);
FORCEPROP 3 LASTPIN (-3475 2625) SIG_NAME M_E_CPU1_SB_DQ<28>
J 0
(-3465 2635);
DISPLAY 0.659574 (-3465 2635);
PAINT MONO (-3465 2635);
DISPLAY INVISIBLE (-3465 2635);
FORCEPROP 1 LASTPIN (-3475 2625) BN 28
J 0
(-3487 2633);
DISPLAY 0.489362 (-3487 2633);
PAINT GREEN (-3487 2633);
FORCEPROP 2 LAST CDS_LIB mstr_standard
J 0
(-3425 2625);
DISPLAY 0.723404 (-3425 2625);
PAINT MONO (-3425 2625);
DISPLAY INVISIBLE (-3425 2625);
FORCEPROP 1 LAST BODY_TYPE PLUMBING
J 0
(-3425 2675);
DISPLAY 0.872340 (-3425 2675);
PAINT GREEN (-3425 2675);
DISPLAY INVISIBLE (-3425 2675);
FORCEPROP 1 LAST HDL_TAP TRUE
J 0
(-3100 2500);
DISPLAY 0.872340 (-3100 2500);
DISPLAY INVISIBLE (-3100 2500);
FORCEPROP 1 LAST PATH I222
J 0
(-3427 2625);
DISPLAY 0.872340 (-3427 2625);
PAINT GREEN (-3427 2625);
DISPLAY INVISIBLE (-3427 2625);
FORCEADD TAP..1
(-3425 2675);
FORCEPROP 3 LASTPIN (-3475 2675) SIG_NAME M_E_CPU1_SB_DQ<27>
J 0
(-3465 2685);
DISPLAY 0.659574 (-3465 2685);
PAINT MONO (-3465 2685);
DISPLAY INVISIBLE (-3465 2685);
FORCEPROP 1 LASTPIN (-3475 2675) BN 27
J 0
(-3487 2683);
DISPLAY 0.489362 (-3487 2683);
PAINT GREEN (-3487 2683);
FORCEPROP 2 LAST CDS_LIB mstr_standard
J 0
(-3425 2675);
DISPLAY 0.723404 (-3425 2675);
PAINT MONO (-3425 2675);
DISPLAY INVISIBLE (-3425 2675);
FORCEPROP 1 LAST BODY_TYPE PLUMBING
J 0
(-3425 2725);
DISPLAY 0.872340 (-3425 2725);
PAINT GREEN (-3425 2725);
DISPLAY INVISIBLE (-3425 2725);
FORCEPROP 1 LAST HDL_TAP TRUE
J 0
(-3100 2550);
DISPLAY 0.872340 (-3100 2550);
DISPLAY INVISIBLE (-3100 2550);
FORCEPROP 1 LAST PATH I223
J 0
(-3427 2675);
DISPLAY 0.872340 (-3427 2675);
PAINT GREEN (-3427 2675);
DISPLAY INVISIBLE (-3427 2675);
FORCEADD TAP..1
(-3425 2575);
FORCEPROP 3 LASTPIN (-3475 2575) SIG_NAME M_E_CPU1_SB_DQ<29>
J 0
(-3465 2585);
DISPLAY 0.659574 (-3465 2585);
PAINT MONO (-3465 2585);
DISPLAY INVISIBLE (-3465 2585);
FORCEPROP 1 LASTPIN (-3475 2575) BN 29
J 0
(-3487 2583);
DISPLAY 0.489362 (-3487 2583);
PAINT GREEN (-3487 2583);
FORCEPROP 2 LAST CDS_LIB mstr_standard
J 0
(-3425 2575);
DISPLAY 0.723404 (-3425 2575);
PAINT MONO (-3425 2575);
DISPLAY INVISIBLE (-3425 2575);
FORCEPROP 1 LAST BODY_TYPE PLUMBING
J 0
(-3425 2625);
DISPLAY 0.872340 (-3425 2625);
PAINT GREEN (-3425 2625);
DISPLAY INVISIBLE (-3425 2625);
FORCEPROP 1 LAST HDL_TAP TRUE
J 0
(-3100 2450);
DISPLAY 0.872340 (-3100 2450);
DISPLAY INVISIBLE (-3100 2450);
FORCEPROP 1 LAST PATH I224
J 0
(-3427 2575);
DISPLAY 0.872340 (-3427 2575);
PAINT GREEN (-3427 2575);
DISPLAY INVISIBLE (-3427 2575);
FORCEADD TAP..1
(-3425 2525);
FORCEPROP 3 LASTPIN (-3475 2525) SIG_NAME M_E_CPU1_SB_DQ<30>
J 0
(-3465 2535);
DISPLAY 0.659574 (-3465 2535);
PAINT MONO (-3465 2535);
DISPLAY INVISIBLE (-3465 2535);
FORCEPROP 1 LASTPIN (-3475 2525) BN 30
J 0
(-3487 2533);
DISPLAY 0.489362 (-3487 2533);
PAINT GREEN (-3487 2533);
FORCEPROP 2 LAST CDS_LIB mstr_standard
J 0
(-3425 2525);
DISPLAY 0.723404 (-3425 2525);
PAINT MONO (-3425 2525);
DISPLAY INVISIBLE (-3425 2525);
FORCEPROP 1 LAST BODY_TYPE PLUMBING
J 0
(-3425 2575);
DISPLAY 0.872340 (-3425 2575);
PAINT GREEN (-3425 2575);
DISPLAY INVISIBLE (-3425 2575);
FORCEPROP 1 LAST HDL_TAP TRUE
J 0
(-3100 2400);
DISPLAY 0.872340 (-3100 2400);
DISPLAY INVISIBLE (-3100 2400);
FORCEPROP 1 LAST PATH I225
J 0
(-3427 2525);
DISPLAY 0.872340 (-3427 2525);
PAINT GREEN (-3427 2525);
DISPLAY INVISIBLE (-3427 2525);
FORCEADD TAP..1
(-3425 2475);
FORCEPROP 3 LASTPIN (-3475 2475) SIG_NAME M_E_CPU1_SB_DQ<31>
J 0
(-3465 2485);
DISPLAY 0.659574 (-3465 2485);
PAINT MONO (-3465 2485);
DISPLAY INVISIBLE (-3465 2485);
FORCEPROP 1 LASTPIN (-3475 2475) BN 31
J 0
(-3487 2483);
DISPLAY 0.489362 (-3487 2483);
PAINT GREEN (-3487 2483);
FORCEPROP 2 LAST CDS_LIB mstr_standard
J 0
(-3425 2475);
DISPLAY 0.723404 (-3425 2475);
PAINT MONO (-3425 2475);
DISPLAY INVISIBLE (-3425 2475);
FORCEPROP 1 LAST BODY_TYPE PLUMBING
J 0
(-3425 2525);
DISPLAY 0.872340 (-3425 2525);
PAINT GREEN (-3425 2525);
DISPLAY INVISIBLE (-3425 2525);
FORCEPROP 1 LAST HDL_TAP TRUE
J 0
(-3100 2350);
DISPLAY 0.872340 (-3100 2350);
DISPLAY INVISIBLE (-3100 2350);
FORCEPROP 1 LAST PATH I226
J 0
(-3427 2475);
DISPLAY 0.872340 (-3427 2475);
PAINT GREEN (-3427 2475);
DISPLAY INVISIBLE (-3427 2475);
FORCEADD TAP..1
(-3425 2375);
FORCEPROP 3 LASTPIN (-3475 2375) SIG_NAME M_E_CPU1_SA_CB<0>
J 0
(-3465 2385);
DISPLAY 0.659574 (-3465 2385);
PAINT MONO (-3465 2385);
DISPLAY INVISIBLE (-3465 2385);
FORCEPROP 1 LASTPIN (-3475 2375) BN 0
J 0
(-3487 2383);
DISPLAY 0.489362 (-3487 2383);
PAINT GREEN (-3487 2383);
FORCEPROP 2 LAST CDS_LIB mstr_standard
J 2
(-3425 2375);
DISPLAY 0.723404 (-3425 2375);
PAINT MONO (-3425 2375);
DISPLAY INVISIBLE (-3425 2375);
FORCEPROP 1 LAST BODY_TYPE PLUMBING
J 0
(-3425 2425);
DISPLAY 0.872340 (-3425 2425);
PAINT GREEN (-3425 2425);
DISPLAY INVISIBLE (-3425 2425);
FORCEPROP 1 LAST HDL_TAP TRUE
J 0
(-3100 2250);
DISPLAY 0.872340 (-3100 2250);
DISPLAY INVISIBLE (-3100 2250);
FORCEPROP 1 LAST PATH I227
J 0
(-3427 2375);
DISPLAY 0.872340 (-3427 2375);
PAINT GREEN (-3427 2375);
DISPLAY INVISIBLE (-3427 2375);
FORCEADD TAP..1
(-3425 2325);
FORCEPROP 3 LASTPIN (-3475 2325) SIG_NAME M_E_CPU1_SA_CB<1>
J 0
(-3465 2335);
DISPLAY 0.659574 (-3465 2335);
PAINT MONO (-3465 2335);
DISPLAY INVISIBLE (-3465 2335);
FORCEPROP 1 LASTPIN (-3475 2325) BN 1
J 0
(-3487 2333);
DISPLAY 0.489362 (-3487 2333);
PAINT GREEN (-3487 2333);
FORCEPROP 2 LAST CDS_LIB mstr_standard
J 2
(-3425 2325);
DISPLAY 0.723404 (-3425 2325);
PAINT MONO (-3425 2325);
DISPLAY INVISIBLE (-3425 2325);
FORCEPROP 1 LAST BODY_TYPE PLUMBING
J 0
(-3425 2375);
DISPLAY 0.872340 (-3425 2375);
PAINT GREEN (-3425 2375);
DISPLAY INVISIBLE (-3425 2375);
FORCEPROP 1 LAST HDL_TAP TRUE
J 0
(-3100 2200);
DISPLAY 0.872340 (-3100 2200);
DISPLAY INVISIBLE (-3100 2200);
FORCEPROP 1 LAST PATH I228
J 0
(-3427 2325);
DISPLAY 0.872340 (-3427 2325);
PAINT GREEN (-3427 2325);
DISPLAY INVISIBLE (-3427 2325);
FORCEADD TAP..1
(-3425 2225);
FORCEPROP 3 LASTPIN (-3475 2225) SIG_NAME M_E_CPU1_SA_CB<3>
J 0
(-3465 2235);
DISPLAY 0.659574 (-3465 2235);
PAINT MONO (-3465 2235);
DISPLAY INVISIBLE (-3465 2235);
FORCEPROP 1 LASTPIN (-3475 2225) BN 3
J 0
(-3487 2233);
DISPLAY 0.489362 (-3487 2233);
PAINT GREEN (-3487 2233);
FORCEPROP 2 LAST CDS_LIB mstr_standard
J 2
(-3425 2225);
DISPLAY 0.723404 (-3425 2225);
PAINT MONO (-3425 2225);
DISPLAY INVISIBLE (-3425 2225);
FORCEPROP 1 LAST BODY_TYPE PLUMBING
J 0
(-3425 2275);
DISPLAY 0.872340 (-3425 2275);
PAINT GREEN (-3425 2275);
DISPLAY INVISIBLE (-3425 2275);
FORCEPROP 1 LAST HDL_TAP TRUE
J 0
(-3100 2100);
DISPLAY 0.872340 (-3100 2100);
DISPLAY INVISIBLE (-3100 2100);
FORCEPROP 1 LAST PATH I229
J 0
(-3427 2225);
DISPLAY 0.872340 (-3427 2225);
PAINT GREEN (-3427 2225);
DISPLAY INVISIBLE (-3427 2225);
FORCEADD TAP..1
(-3425 2275);
FORCEPROP 3 LASTPIN (-3475 2275) SIG_NAME M_E_CPU1_SA_CB<2>
J 0
(-3465 2285);
DISPLAY 0.659574 (-3465 2285);
PAINT MONO (-3465 2285);
DISPLAY INVISIBLE (-3465 2285);
FORCEPROP 1 LASTPIN (-3475 2275) BN 2
J 0
(-3487 2283);
DISPLAY 0.489362 (-3487 2283);
PAINT GREEN (-3487 2283);
FORCEPROP 2 LAST CDS_LIB mstr_standard
J 2
(-3425 2275);
DISPLAY 0.723404 (-3425 2275);
PAINT MONO (-3425 2275);
DISPLAY INVISIBLE (-3425 2275);
FORCEPROP 1 LAST BODY_TYPE PLUMBING
J 0
(-3425 2325);
DISPLAY 0.872340 (-3425 2325);
PAINT GREEN (-3425 2325);
DISPLAY INVISIBLE (-3425 2325);
FORCEPROP 1 LAST HDL_TAP TRUE
J 0
(-3100 2150);
DISPLAY 0.872340 (-3100 2150);
DISPLAY INVISIBLE (-3100 2150);
FORCEPROP 1 LAST PATH I230
J 0
(-3427 2275);
DISPLAY 0.872340 (-3427 2275);
PAINT GREEN (-3427 2275);
DISPLAY INVISIBLE (-3427 2275);
FORCEADD TAP..1
(-3425 2125);
FORCEPROP 3 LASTPIN (-3475 2125) SIG_NAME M_E_CPU1_SA_CB<5>
J 0
(-3465 2135);
DISPLAY 0.659574 (-3465 2135);
PAINT MONO (-3465 2135);
DISPLAY INVISIBLE (-3465 2135);
FORCEPROP 1 LASTPIN (-3475 2125) BN 5
J 0
(-3487 2133);
DISPLAY 0.489362 (-3487 2133);
PAINT GREEN (-3487 2133);
FORCEPROP 2 LAST CDS_LIB mstr_standard
J 2
(-3425 2125);
DISPLAY 0.723404 (-3425 2125);
PAINT MONO (-3425 2125);
DISPLAY INVISIBLE (-3425 2125);
FORCEPROP 1 LAST BODY_TYPE PLUMBING
J 0
(-3425 2175);
DISPLAY 0.872340 (-3425 2175);
PAINT GREEN (-3425 2175);
DISPLAY INVISIBLE (-3425 2175);
FORCEPROP 1 LAST HDL_TAP TRUE
J 0
(-3100 2000);
DISPLAY 0.872340 (-3100 2000);
DISPLAY INVISIBLE (-3100 2000);
FORCEPROP 1 LAST PATH I231
J 0
(-3427 2125);
DISPLAY 0.872340 (-3427 2125);
PAINT GREEN (-3427 2125);
DISPLAY INVISIBLE (-3427 2125);
FORCEADD TAP..1
(-3425 2175);
FORCEPROP 3 LASTPIN (-3475 2175) SIG_NAME M_E_CPU1_SA_CB<4>
J 0
(-3465 2185);
DISPLAY 0.659574 (-3465 2185);
PAINT MONO (-3465 2185);
DISPLAY INVISIBLE (-3465 2185);
FORCEPROP 1 LASTPIN (-3475 2175) BN 4
J 0
(-3487 2183);
DISPLAY 0.489362 (-3487 2183);
PAINT GREEN (-3487 2183);
FORCEPROP 2 LAST CDS_LIB mstr_standard
J 2
(-3425 2175);
DISPLAY 0.723404 (-3425 2175);
PAINT MONO (-3425 2175);
DISPLAY INVISIBLE (-3425 2175);
FORCEPROP 1 LAST BODY_TYPE PLUMBING
J 0
(-3425 2225);
DISPLAY 0.872340 (-3425 2225);
PAINT GREEN (-3425 2225);
DISPLAY INVISIBLE (-3425 2225);
FORCEPROP 1 LAST HDL_TAP TRUE
J 0
(-3100 2050);
DISPLAY 0.872340 (-3100 2050);
DISPLAY INVISIBLE (-3100 2050);
FORCEPROP 1 LAST PATH I232
J 0
(-3427 2175);
DISPLAY 0.872340 (-3427 2175);
PAINT GREEN (-3427 2175);
DISPLAY INVISIBLE (-3427 2175);
FORCEADD TAP..1
(-3425 2075);
FORCEPROP 3 LASTPIN (-3475 2075) SIG_NAME M_E_CPU1_SA_CB<6>
J 0
(-3465 2085);
DISPLAY 0.659574 (-3465 2085);
PAINT MONO (-3465 2085);
DISPLAY INVISIBLE (-3465 2085);
FORCEPROP 1 LASTPIN (-3475 2075) BN 6
J 0
(-3487 2083);
DISPLAY 0.489362 (-3487 2083);
PAINT GREEN (-3487 2083);
FORCEPROP 2 LAST CDS_LIB mstr_standard
J 2
(-3425 2075);
DISPLAY 0.723404 (-3425 2075);
PAINT MONO (-3425 2075);
DISPLAY INVISIBLE (-3425 2075);
FORCEPROP 1 LAST BODY_TYPE PLUMBING
J 0
(-3425 2125);
DISPLAY 0.872340 (-3425 2125);
PAINT GREEN (-3425 2125);
DISPLAY INVISIBLE (-3425 2125);
FORCEPROP 1 LAST HDL_TAP TRUE
J 0
(-3100 1950);
DISPLAY 0.872340 (-3100 1950);
DISPLAY INVISIBLE (-3100 1950);
FORCEPROP 1 LAST PATH I233
J 0
(-3427 2075);
DISPLAY 0.872340 (-3427 2075);
PAINT GREEN (-3427 2075);
DISPLAY INVISIBLE (-3427 2075);
FORCEADD OFFPAGE..6
R 2
(-2825 1975);
FORCEPROP 2 LAST $XR0 102 
J 0
(-2611 1975);
DISPLAY 0.638298 (-2611 1975);
PAINT MONO (-2611 1975);
FORCEPROP 2 LAST CDS_LIB mstr_standard
J 2
(-2825 1975);
DISPLAY 0.723404 (-2825 1975);
PAINT MONO (-2825 1975);
DISPLAY INVISIBLE (-2825 1975);
FORCEPROP 1 LAST OFFPAGE TRUE
J 2
(-3150 1850);
DISPLAY 0.872340 (-3150 1850);
PAINT GREEN (-3150 1850);
DISPLAY INVISIBLE (-3150 1850);
FORCEPROP 1 LAST COMMENT_BODY TRUE
J 2
(-2925 1900);
DISPLAY 0.872340 (-2925 1900);
PAINT GREEN (-2925 1900);
DISPLAY INVISIBLE (-2925 1900);
FORCEPROP 2 LAST PATH I234
J 0
(-2600 2025);
DISPLAY 1.021277 (-2600 2025);
DISPLAY INVISIBLE (-2600 2025);
FORCEADD TAP..1
(-3425 2025);
FORCEPROP 3 LASTPIN (-3475 2025) SIG_NAME M_E_CPU1_SA_CB<7>
J 0
(-3465 2035);
DISPLAY 0.659574 (-3465 2035);
PAINT MONO (-3465 2035);
DISPLAY INVISIBLE (-3465 2035);
FORCEPROP 1 LASTPIN (-3475 2025) BN 7
J 0
(-3487 2033);
DISPLAY 0.489362 (-3487 2033);
PAINT GREEN (-3487 2033);
FORCEPROP 2 LAST CDS_LIB mstr_standard
J 2
(-3425 2025);
DISPLAY 0.723404 (-3425 2025);
PAINT MONO (-3425 2025);
DISPLAY INVISIBLE (-3425 2025);
FORCEPROP 1 LAST BODY_TYPE PLUMBING
J 0
(-3425 2075);
DISPLAY 0.872340 (-3425 2075);
PAINT GREEN (-3425 2075);
DISPLAY INVISIBLE (-3425 2075);
FORCEPROP 1 LAST HDL_TAP TRUE
J 0
(-3100 1900);
DISPLAY 0.872340 (-3100 1900);
DISPLAY INVISIBLE (-3100 1900);
FORCEPROP 1 LAST PATH I235
J 0
(-3427 2025);
DISPLAY 0.872340 (-3427 2025);
PAINT GREEN (-3427 2025);
DISPLAY INVISIBLE (-3427 2025);
FORCEADD TAP..1
(-3425 1925);
FORCEPROP 3 LASTPIN (-3475 1925) SIG_NAME M_E_CPU1_SB_CB<0>
J 0
(-3465 1935);
DISPLAY 0.659574 (-3465 1935);
PAINT MONO (-3465 1935);
DISPLAY INVISIBLE (-3465 1935);
FORCEPROP 1 LASTPIN (-3475 1925) BN 0
J 0
(-3487 1933);
DISPLAY 0.489362 (-3487 1933);
PAINT GREEN (-3487 1933);
FORCEPROP 2 LAST CDS_LIB mstr_standard
J 2
(-3425 1925);
DISPLAY 0.723404 (-3425 1925);
PAINT MONO (-3425 1925);
DISPLAY INVISIBLE (-3425 1925);
FORCEPROP 1 LAST BODY_TYPE PLUMBING
J 0
(-3425 1975);
DISPLAY 0.872340 (-3425 1975);
PAINT GREEN (-3425 1975);
DISPLAY INVISIBLE (-3425 1975);
FORCEPROP 1 LAST HDL_TAP TRUE
J 0
(-3100 1800);
DISPLAY 0.872340 (-3100 1800);
DISPLAY INVISIBLE (-3100 1800);
FORCEPROP 1 LAST PATH I236
J 0
(-3427 1925);
DISPLAY 0.872340 (-3427 1925);
PAINT GREEN (-3427 1925);
DISPLAY INVISIBLE (-3427 1925);
FORCEADD TAP..1
(-3425 1875);
FORCEPROP 3 LASTPIN (-3475 1875) SIG_NAME M_E_CPU1_SB_CB<1>
J 0
(-3465 1885);
DISPLAY 0.659574 (-3465 1885);
PAINT MONO (-3465 1885);
DISPLAY INVISIBLE (-3465 1885);
FORCEPROP 1 LASTPIN (-3475 1875) BN 1
J 0
(-3487 1883);
DISPLAY 0.489362 (-3487 1883);
PAINT GREEN (-3487 1883);
FORCEPROP 2 LAST CDS_LIB mstr_standard
J 2
(-3425 1875);
DISPLAY 0.723404 (-3425 1875);
PAINT MONO (-3425 1875);
DISPLAY INVISIBLE (-3425 1875);
FORCEPROP 1 LAST BODY_TYPE PLUMBING
J 0
(-3425 1925);
DISPLAY 0.872340 (-3425 1925);
PAINT GREEN (-3425 1925);
DISPLAY INVISIBLE (-3425 1925);
FORCEPROP 1 LAST HDL_TAP TRUE
J 0
(-3100 1750);
DISPLAY 0.872340 (-3100 1750);
DISPLAY INVISIBLE (-3100 1750);
FORCEPROP 1 LAST PATH I237
J 0
(-3427 1875);
DISPLAY 0.872340 (-3427 1875);
PAINT GREEN (-3427 1875);
DISPLAY INVISIBLE (-3427 1875);
FORCEADD TAP..1
(-3425 1825);
FORCEPROP 3 LASTPIN (-3475 1825) SIG_NAME M_E_CPU1_SB_CB<2>
J 0
(-3465 1835);
DISPLAY 0.659574 (-3465 1835);
PAINT MONO (-3465 1835);
DISPLAY INVISIBLE (-3465 1835);
FORCEPROP 1 LASTPIN (-3475 1825) BN 2
J 0
(-3487 1833);
DISPLAY 0.489362 (-3487 1833);
PAINT GREEN (-3487 1833);
FORCEPROP 2 LAST CDS_LIB mstr_standard
J 2
(-3425 1825);
DISPLAY 0.723404 (-3425 1825);
PAINT MONO (-3425 1825);
DISPLAY INVISIBLE (-3425 1825);
FORCEPROP 1 LAST BODY_TYPE PLUMBING
J 0
(-3425 1875);
DISPLAY 0.872340 (-3425 1875);
PAINT GREEN (-3425 1875);
DISPLAY INVISIBLE (-3425 1875);
FORCEPROP 1 LAST HDL_TAP TRUE
J 0
(-3100 1700);
DISPLAY 0.872340 (-3100 1700);
DISPLAY INVISIBLE (-3100 1700);
FORCEPROP 1 LAST PATH I238
J 0
(-3427 1825);
DISPLAY 0.872340 (-3427 1825);
PAINT GREEN (-3427 1825);
DISPLAY INVISIBLE (-3427 1825);
FORCEADD TAP..1
(-3425 1775);
FORCEPROP 3 LASTPIN (-3475 1775) SIG_NAME M_E_CPU1_SB_CB<3>
J 0
(-3465 1785);
DISPLAY 0.659574 (-3465 1785);
PAINT MONO (-3465 1785);
DISPLAY INVISIBLE (-3465 1785);
FORCEPROP 1 LASTPIN (-3475 1775) BN 3
J 0
(-3487 1783);
DISPLAY 0.489362 (-3487 1783);
PAINT GREEN (-3487 1783);
FORCEPROP 2 LAST CDS_LIB mstr_standard
J 2
(-3425 1775);
DISPLAY 0.723404 (-3425 1775);
PAINT MONO (-3425 1775);
DISPLAY INVISIBLE (-3425 1775);
FORCEPROP 1 LAST BODY_TYPE PLUMBING
J 0
(-3425 1825);
DISPLAY 0.872340 (-3425 1825);
PAINT GREEN (-3425 1825);
DISPLAY INVISIBLE (-3425 1825);
FORCEPROP 1 LAST HDL_TAP TRUE
J 0
(-3100 1650);
DISPLAY 0.872340 (-3100 1650);
DISPLAY INVISIBLE (-3100 1650);
FORCEPROP 1 LAST PATH I239
J 0
(-3427 1775);
DISPLAY 0.872340 (-3427 1775);
PAINT GREEN (-3427 1775);
DISPLAY INVISIBLE (-3427 1775);
FORCEADD TAP..1
(-3425 1675);
FORCEPROP 3 LASTPIN (-3475 1675) SIG_NAME M_E_CPU1_SB_CB<5>
J 0
(-3465 1685);
DISPLAY 0.659574 (-3465 1685);
PAINT MONO (-3465 1685);
DISPLAY INVISIBLE (-3465 1685);
FORCEPROP 1 LASTPIN (-3475 1675) BN 5
J 0
(-3487 1683);
DISPLAY 0.489362 (-3487 1683);
PAINT GREEN (-3487 1683);
FORCEPROP 2 LAST CDS_LIB mstr_standard
J 2
(-3425 1675);
DISPLAY 0.723404 (-3425 1675);
PAINT MONO (-3425 1675);
DISPLAY INVISIBLE (-3425 1675);
FORCEPROP 1 LAST BODY_TYPE PLUMBING
J 0
(-3425 1725);
DISPLAY 0.872340 (-3425 1725);
PAINT GREEN (-3425 1725);
DISPLAY INVISIBLE (-3425 1725);
FORCEPROP 1 LAST HDL_TAP TRUE
J 0
(-3100 1550);
DISPLAY 0.872340 (-3100 1550);
DISPLAY INVISIBLE (-3100 1550);
FORCEPROP 1 LAST PATH I240
J 0
(-3427 1675);
DISPLAY 0.872340 (-3427 1675);
PAINT GREEN (-3427 1675);
DISPLAY INVISIBLE (-3427 1675);
FORCEADD TAP..1
(-3425 1725);
FORCEPROP 3 LASTPIN (-3475 1725) SIG_NAME M_E_CPU1_SB_CB<4>
J 0
(-3465 1735);
DISPLAY 0.659574 (-3465 1735);
PAINT MONO (-3465 1735);
DISPLAY INVISIBLE (-3465 1735);
FORCEPROP 1 LASTPIN (-3475 1725) BN 4
J 0
(-3487 1733);
DISPLAY 0.489362 (-3487 1733);
PAINT GREEN (-3487 1733);
FORCEPROP 2 LAST CDS_LIB mstr_standard
J 2
(-3425 1725);
DISPLAY 0.723404 (-3425 1725);
PAINT MONO (-3425 1725);
DISPLAY INVISIBLE (-3425 1725);
FORCEPROP 1 LAST BODY_TYPE PLUMBING
J 0
(-3425 1775);
DISPLAY 0.872340 (-3425 1775);
PAINT GREEN (-3425 1775);
DISPLAY INVISIBLE (-3425 1775);
FORCEPROP 1 LAST HDL_TAP TRUE
J 0
(-3100 1600);
DISPLAY 0.872340 (-3100 1600);
DISPLAY INVISIBLE (-3100 1600);
FORCEPROP 1 LAST PATH I241
J 0
(-3427 1725);
DISPLAY 0.872340 (-3427 1725);
PAINT GREEN (-3427 1725);
DISPLAY INVISIBLE (-3427 1725);
FORCEADD TAP..1
(-3425 1625);
FORCEPROP 3 LASTPIN (-3475 1625) SIG_NAME M_E_CPU1_SB_CB<6>
J 0
(-3465 1635);
DISPLAY 0.659574 (-3465 1635);
PAINT MONO (-3465 1635);
DISPLAY INVISIBLE (-3465 1635);
FORCEPROP 1 LASTPIN (-3475 1625) BN 6
J 0
(-3487 1633);
DISPLAY 0.489362 (-3487 1633);
PAINT GREEN (-3487 1633);
FORCEPROP 2 LAST CDS_LIB mstr_standard
J 2
(-3425 1625);
DISPLAY 0.723404 (-3425 1625);
PAINT MONO (-3425 1625);
DISPLAY INVISIBLE (-3425 1625);
FORCEPROP 1 LAST BODY_TYPE PLUMBING
J 0
(-3425 1675);
DISPLAY 0.872340 (-3425 1675);
PAINT GREEN (-3425 1675);
DISPLAY INVISIBLE (-3425 1675);
FORCEPROP 1 LAST HDL_TAP TRUE
J 0
(-3100 1500);
DISPLAY 0.872340 (-3100 1500);
DISPLAY INVISIBLE (-3100 1500);
FORCEPROP 1 LAST PATH I242
J 0
(-3427 1625);
DISPLAY 0.872340 (-3427 1625);
PAINT GREEN (-3427 1625);
DISPLAY INVISIBLE (-3427 1625);
FORCEADD TAP..1
(-3425 1575);
FORCEPROP 3 LASTPIN (-3475 1575) SIG_NAME M_E_CPU1_SB_CB<7>
J 0
(-3465 1585);
DISPLAY 0.659574 (-3465 1585);
PAINT MONO (-3465 1585);
DISPLAY INVISIBLE (-3465 1585);
FORCEPROP 1 LASTPIN (-3475 1575) BN 7
J 0
(-3487 1583);
DISPLAY 0.489362 (-3487 1583);
PAINT GREEN (-3487 1583);
FORCEPROP 2 LAST CDS_LIB mstr_standard
J 2
(-3425 1575);
DISPLAY 0.723404 (-3425 1575);
PAINT MONO (-3425 1575);
DISPLAY INVISIBLE (-3425 1575);
FORCEPROP 1 LAST BODY_TYPE PLUMBING
J 0
(-3425 1625);
DISPLAY 0.872340 (-3425 1625);
PAINT GREEN (-3425 1625);
DISPLAY INVISIBLE (-3425 1625);
FORCEPROP 1 LAST HDL_TAP TRUE
J 0
(-3100 1450);
DISPLAY 0.872340 (-3100 1450);
DISPLAY INVISIBLE (-3100 1450);
FORCEPROP 1 LAST PATH I243
J 0
(-3427 1575);
DISPLAY 0.872340 (-3427 1575);
PAINT GREEN (-3427 1575);
DISPLAY INVISIBLE (-3427 1575);
FORCEADD TAP..1
R 2
(-5850 5975);
FORCEPROP 3 LASTPIN (-5800 5975) SIG_NAME M_E_CPU1_SA_DQS_DP<0>
J 0
(-5790 5985);
DISPLAY 0.659574 (-5790 5985);
PAINT MONO (-5790 5985);
DISPLAY INVISIBLE (-5790 5985);
FORCEPROP 1 LASTPIN (-5800 5975) BN 0
J 2
(-5788 5983);
DISPLAY 0.489362 (-5788 5983);
PAINT GREEN (-5788 5983);
FORCEPROP 2 LAST CDS_LIB mstr_standard
J 2
(-5850 5975);
DISPLAY 0.723404 (-5850 5975);
PAINT MONO (-5850 5975);
DISPLAY INVISIBLE (-5850 5975);
FORCEPROP 1 LAST BODY_TYPE PLUMBING
J 2
(-5850 6025);
DISPLAY 0.872340 (-5850 6025);
PAINT GREEN (-5850 6025);
DISPLAY INVISIBLE (-5850 6025);
FORCEPROP 1 LAST HDL_TAP TRUE
J 2
(-6175 5850);
DISPLAY 0.872340 (-6175 5850);
DISPLAY INVISIBLE (-6175 5850);
FORCEPROP 1 LAST PATH I244
J 2
(-5848 5975);
DISPLAY 0.872340 (-5848 5975);
PAINT GREEN (-5848 5975);
DISPLAY INVISIBLE (-5848 5975);
FORCEADD TAP..1
R 2
(-5850 5875);
FORCEPROP 3 LASTPIN (-5800 5875) SIG_NAME M_E_CPU1_SA_DQS_DP<1>
J 0
(-5790 5885);
DISPLAY 0.659574 (-5790 5885);
PAINT MONO (-5790 5885);
DISPLAY INVISIBLE (-5790 5885);
FORCEPROP 1 LASTPIN (-5800 5875) BN 1
J 2
(-5788 5883);
DISPLAY 0.489362 (-5788 5883);
PAINT GREEN (-5788 5883);
FORCEPROP 2 LAST CDS_LIB mstr_standard
J 2
(-5850 5875);
DISPLAY 0.723404 (-5850 5875);
PAINT MONO (-5850 5875);
DISPLAY INVISIBLE (-5850 5875);
FORCEPROP 1 LAST BODY_TYPE PLUMBING
J 2
(-5850 5925);
DISPLAY 0.872340 (-5850 5925);
PAINT GREEN (-5850 5925);
DISPLAY INVISIBLE (-5850 5925);
FORCEPROP 1 LAST HDL_TAP TRUE
J 2
(-6175 5750);
DISPLAY 0.872340 (-6175 5750);
DISPLAY INVISIBLE (-6175 5750);
FORCEPROP 1 LAST PATH I245
J 2
(-5848 5875);
DISPLAY 0.872340 (-5848 5875);
PAINT GREEN (-5848 5875);
DISPLAY INVISIBLE (-5848 5875);
FORCEADD TAP..1
R 2
(-5850 5675);
FORCEPROP 3 LASTPIN (-5800 5675) SIG_NAME M_E_CPU1_SA_DQS_DP<3>
J 0
(-5790 5685);
DISPLAY 0.659574 (-5790 5685);
PAINT MONO (-5790 5685);
DISPLAY INVISIBLE (-5790 5685);
FORCEPROP 1 LASTPIN (-5800 5675) BN 3
J 2
(-5788 5683);
DISPLAY 0.489362 (-5788 5683);
PAINT GREEN (-5788 5683);
FORCEPROP 2 LAST CDS_LIB mstr_standard
J 2
(-5850 5675);
DISPLAY 0.723404 (-5850 5675);
PAINT MONO (-5850 5675);
DISPLAY INVISIBLE (-5850 5675);
FORCEPROP 1 LAST BODY_TYPE PLUMBING
J 2
(-5850 5725);
DISPLAY 0.872340 (-5850 5725);
PAINT GREEN (-5850 5725);
DISPLAY INVISIBLE (-5850 5725);
FORCEPROP 1 LAST HDL_TAP TRUE
J 2
(-6175 5550);
DISPLAY 0.872340 (-6175 5550);
DISPLAY INVISIBLE (-6175 5550);
FORCEPROP 1 LAST PATH I246
J 2
(-5848 5675);
DISPLAY 0.872340 (-5848 5675);
PAINT GREEN (-5848 5675);
DISPLAY INVISIBLE (-5848 5675);
FORCEADD TAP..1
R 2
(-5850 5775);
FORCEPROP 3 LASTPIN (-5800 5775) SIG_NAME M_E_CPU1_SA_DQS_DP<2>
J 0
(-5790 5785);
DISPLAY 0.659574 (-5790 5785);
PAINT MONO (-5790 5785);
DISPLAY INVISIBLE (-5790 5785);
FORCEPROP 1 LASTPIN (-5800 5775) BN 2
J 2
(-5788 5783);
DISPLAY 0.489362 (-5788 5783);
PAINT GREEN (-5788 5783);
FORCEPROP 2 LAST CDS_LIB mstr_standard
J 2
(-5850 5775);
DISPLAY 0.723404 (-5850 5775);
PAINT MONO (-5850 5775);
DISPLAY INVISIBLE (-5850 5775);
FORCEPROP 1 LAST BODY_TYPE PLUMBING
J 2
(-5850 5825);
DISPLAY 0.872340 (-5850 5825);
PAINT GREEN (-5850 5825);
DISPLAY INVISIBLE (-5850 5825);
FORCEPROP 1 LAST HDL_TAP TRUE
J 2
(-6175 5650);
DISPLAY 0.872340 (-6175 5650);
DISPLAY INVISIBLE (-6175 5650);
FORCEPROP 1 LAST PATH I247
J 2
(-5848 5775);
DISPLAY 0.872340 (-5848 5775);
PAINT GREEN (-5848 5775);
DISPLAY INVISIBLE (-5848 5775);
FORCEADD TAP..1
R 2
(-6050 5925);
FORCEPROP 3 LASTPIN (-6000 5925) SIG_NAME M_E_CPU1_SA_DQS_DN<0>
J 0
(-5990 5935);
DISPLAY 0.659574 (-5990 5935);
PAINT MONO (-5990 5935);
DISPLAY INVISIBLE (-5990 5935);
FORCEPROP 1 LASTPIN (-6000 5925) BN 0
J 2
(-5988 5933);
DISPLAY 0.489362 (-5988 5933);
PAINT GREEN (-5988 5933);
FORCEPROP 2 LAST CDS_LIB mstr_standard
J 2
(-6050 5925);
DISPLAY 0.723404 (-6050 5925);
PAINT MONO (-6050 5925);
DISPLAY INVISIBLE (-6050 5925);
FORCEPROP 1 LAST BODY_TYPE PLUMBING
J 2
(-6050 5975);
DISPLAY 0.872340 (-6050 5975);
PAINT GREEN (-6050 5975);
DISPLAY INVISIBLE (-6050 5975);
FORCEPROP 1 LAST HDL_TAP TRUE
J 2
(-6375 5800);
DISPLAY 0.872340 (-6375 5800);
DISPLAY INVISIBLE (-6375 5800);
FORCEPROP 1 LAST PATH I248
J 2
(-6048 5925);
DISPLAY 0.872340 (-6048 5925);
PAINT GREEN (-6048 5925);
DISPLAY INVISIBLE (-6048 5925);
FORCEADD TAP..1
R 2
(-6050 5825);
FORCEPROP 3 LASTPIN (-6000 5825) SIG_NAME M_E_CPU1_SA_DQS_DN<1>
J 0
(-5990 5835);
DISPLAY 0.659574 (-5990 5835);
PAINT MONO (-5990 5835);
DISPLAY INVISIBLE (-5990 5835);
FORCEPROP 1 LASTPIN (-6000 5825) BN 1
J 2
(-5988 5833);
DISPLAY 0.489362 (-5988 5833);
PAINT GREEN (-5988 5833);
FORCEPROP 2 LAST CDS_LIB mstr_standard
J 2
(-6050 5825);
DISPLAY 0.723404 (-6050 5825);
PAINT MONO (-6050 5825);
DISPLAY INVISIBLE (-6050 5825);
FORCEPROP 1 LAST BODY_TYPE PLUMBING
J 2
(-6050 5875);
DISPLAY 0.872340 (-6050 5875);
PAINT GREEN (-6050 5875);
DISPLAY INVISIBLE (-6050 5875);
FORCEPROP 1 LAST HDL_TAP TRUE
J 2
(-6375 5700);
DISPLAY 0.872340 (-6375 5700);
DISPLAY INVISIBLE (-6375 5700);
FORCEPROP 1 LAST PATH I249
J 2
(-6048 5825);
DISPLAY 0.872340 (-6048 5825);
PAINT GREEN (-6048 5825);
DISPLAY INVISIBLE (-6048 5825);
FORCEADD TAP..1
R 2
(-6050 5725);
FORCEPROP 3 LASTPIN (-6000 5725) SIG_NAME M_E_CPU1_SA_DQS_DN<2>
J 0
(-5990 5735);
DISPLAY 0.659574 (-5990 5735);
PAINT MONO (-5990 5735);
DISPLAY INVISIBLE (-5990 5735);
FORCEPROP 1 LASTPIN (-6000 5725) BN 2
J 2
(-5988 5733);
DISPLAY 0.489362 (-5988 5733);
PAINT GREEN (-5988 5733);
FORCEPROP 2 LAST CDS_LIB mstr_standard
J 2
(-6050 5725);
DISPLAY 0.723404 (-6050 5725);
PAINT MONO (-6050 5725);
DISPLAY INVISIBLE (-6050 5725);
FORCEPROP 1 LAST BODY_TYPE PLUMBING
J 2
(-6050 5775);
DISPLAY 0.872340 (-6050 5775);
PAINT GREEN (-6050 5775);
DISPLAY INVISIBLE (-6050 5775);
FORCEPROP 1 LAST HDL_TAP TRUE
J 2
(-6375 5600);
DISPLAY 0.872340 (-6375 5600);
DISPLAY INVISIBLE (-6375 5600);
FORCEPROP 1 LAST PATH I250
J 2
(-6048 5725);
DISPLAY 0.872340 (-6048 5725);
PAINT GREEN (-6048 5725);
DISPLAY INVISIBLE (-6048 5725);
FORCEADD TAP..1
R 2
(-5850 5475);
FORCEPROP 3 LASTPIN (-5800 5475) SIG_NAME M_E_CPU1_SA_DQS_DP<5>
J 0
(-5790 5485);
DISPLAY 0.659574 (-5790 5485);
PAINT MONO (-5790 5485);
DISPLAY INVISIBLE (-5790 5485);
FORCEPROP 1 LASTPIN (-5800 5475) BN 5
J 2
(-5788 5483);
DISPLAY 0.489362 (-5788 5483);
PAINT GREEN (-5788 5483);
FORCEPROP 2 LAST CDS_LIB mstr_standard
J 2
(-5850 5475);
DISPLAY 0.723404 (-5850 5475);
PAINT MONO (-5850 5475);
DISPLAY INVISIBLE (-5850 5475);
FORCEPROP 1 LAST BODY_TYPE PLUMBING
J 2
(-5850 5525);
DISPLAY 0.872340 (-5850 5525);
PAINT GREEN (-5850 5525);
DISPLAY INVISIBLE (-5850 5525);
FORCEPROP 1 LAST HDL_TAP TRUE
J 2
(-6175 5350);
DISPLAY 0.872340 (-6175 5350);
DISPLAY INVISIBLE (-6175 5350);
FORCEPROP 1 LAST PATH I251
J 2
(-5848 5475);
DISPLAY 0.872340 (-5848 5475);
PAINT GREEN (-5848 5475);
DISPLAY INVISIBLE (-5848 5475);
FORCEADD TAP..1
R 2
(-5850 5575);
FORCEPROP 3 LASTPIN (-5800 5575) SIG_NAME M_E_CPU1_SA_DQS_DP<4>
J 0
(-5790 5585);
DISPLAY 0.659574 (-5790 5585);
PAINT MONO (-5790 5585);
DISPLAY INVISIBLE (-5790 5585);
FORCEPROP 1 LASTPIN (-5800 5575) BN 4
J 2
(-5788 5583);
DISPLAY 0.489362 (-5788 5583);
PAINT GREEN (-5788 5583);
FORCEPROP 2 LAST CDS_LIB mstr_standard
J 2
(-5850 5575);
DISPLAY 0.723404 (-5850 5575);
PAINT MONO (-5850 5575);
DISPLAY INVISIBLE (-5850 5575);
FORCEPROP 1 LAST BODY_TYPE PLUMBING
J 2
(-5850 5625);
DISPLAY 0.872340 (-5850 5625);
PAINT GREEN (-5850 5625);
DISPLAY INVISIBLE (-5850 5625);
FORCEPROP 1 LAST HDL_TAP TRUE
J 2
(-6175 5450);
DISPLAY 0.872340 (-6175 5450);
DISPLAY INVISIBLE (-6175 5450);
FORCEPROP 1 LAST PATH I252
J 2
(-5848 5575);
DISPLAY 0.872340 (-5848 5575);
PAINT GREEN (-5848 5575);
DISPLAY INVISIBLE (-5848 5575);
FORCEADD TAP..1
R 2
(-5850 5375);
FORCEPROP 3 LASTPIN (-5800 5375) SIG_NAME M_E_CPU1_SA_DQS_DP<6>
J 0
(-5790 5385);
DISPLAY 0.659574 (-5790 5385);
PAINT MONO (-5790 5385);
DISPLAY INVISIBLE (-5790 5385);
FORCEPROP 1 LASTPIN (-5800 5375) BN 6
J 2
(-5788 5383);
DISPLAY 0.489362 (-5788 5383);
PAINT GREEN (-5788 5383);
FORCEPROP 2 LAST CDS_LIB mstr_standard
J 2
(-5850 5375);
DISPLAY 0.723404 (-5850 5375);
PAINT MONO (-5850 5375);
DISPLAY INVISIBLE (-5850 5375);
FORCEPROP 1 LAST BODY_TYPE PLUMBING
J 2
(-5850 5425);
DISPLAY 0.872340 (-5850 5425);
PAINT GREEN (-5850 5425);
DISPLAY INVISIBLE (-5850 5425);
FORCEPROP 1 LAST HDL_TAP TRUE
J 2
(-6175 5250);
DISPLAY 0.872340 (-6175 5250);
DISPLAY INVISIBLE (-6175 5250);
FORCEPROP 1 LAST PATH I253
J 2
(-5848 5375);
DISPLAY 0.872340 (-5848 5375);
PAINT GREEN (-5848 5375);
DISPLAY INVISIBLE (-5848 5375);
FORCEADD TAP..1
R 2
(-5850 5175);
FORCEPROP 3 LASTPIN (-5800 5175) SIG_NAME M_E_CPU1_SA_DQS_DP<8>
J 0
(-5790 5185);
DISPLAY 0.659574 (-5790 5185);
PAINT MONO (-5790 5185);
DISPLAY INVISIBLE (-5790 5185);
FORCEPROP 1 LASTPIN (-5800 5175) BN 8
J 2
(-5788 5183);
DISPLAY 0.489362 (-5788 5183);
PAINT GREEN (-5788 5183);
FORCEPROP 2 LAST CDS_LIB mstr_standard
J 2
(-5850 5175);
DISPLAY 0.723404 (-5850 5175);
PAINT MONO (-5850 5175);
DISPLAY INVISIBLE (-5850 5175);
FORCEPROP 1 LAST BODY_TYPE PLUMBING
J 2
(-5850 5225);
DISPLAY 0.872340 (-5850 5225);
PAINT GREEN (-5850 5225);
DISPLAY INVISIBLE (-5850 5225);
FORCEPROP 1 LAST HDL_TAP TRUE
J 2
(-6175 5050);
DISPLAY 0.872340 (-6175 5050);
DISPLAY INVISIBLE (-6175 5050);
FORCEPROP 1 LAST PATH I254
J 2
(-5848 5175);
DISPLAY 0.872340 (-5848 5175);
PAINT GREEN (-5848 5175);
DISPLAY INVISIBLE (-5848 5175);
FORCEADD TAP..1
R 2
(-5850 5275);
FORCEPROP 3 LASTPIN (-5800 5275) SIG_NAME M_E_CPU1_SA_DQS_DP<7>
J 0
(-5790 5285);
DISPLAY 0.659574 (-5790 5285);
PAINT MONO (-5790 5285);
DISPLAY INVISIBLE (-5790 5285);
FORCEPROP 1 LASTPIN (-5800 5275) BN 7
J 2
(-5788 5283);
DISPLAY 0.489362 (-5788 5283);
PAINT GREEN (-5788 5283);
FORCEPROP 2 LAST CDS_LIB mstr_standard
J 2
(-5850 5275);
DISPLAY 0.723404 (-5850 5275);
PAINT MONO (-5850 5275);
DISPLAY INVISIBLE (-5850 5275);
FORCEPROP 1 LAST BODY_TYPE PLUMBING
J 2
(-5850 5325);
DISPLAY 0.872340 (-5850 5325);
PAINT GREEN (-5850 5325);
DISPLAY INVISIBLE (-5850 5325);
FORCEPROP 1 LAST HDL_TAP TRUE
J 2
(-6175 5150);
DISPLAY 0.872340 (-6175 5150);
DISPLAY INVISIBLE (-6175 5150);
FORCEPROP 1 LAST PATH I255
J 2
(-5848 5275);
DISPLAY 0.872340 (-5848 5275);
PAINT GREEN (-5848 5275);
DISPLAY INVISIBLE (-5848 5275);
FORCEADD TAP..1
R 2
(-6050 5625);
FORCEPROP 3 LASTPIN (-6000 5625) SIG_NAME M_E_CPU1_SA_DQS_DN<3>
J 0
(-5990 5635);
DISPLAY 0.659574 (-5990 5635);
PAINT MONO (-5990 5635);
DISPLAY INVISIBLE (-5990 5635);
FORCEPROP 1 LASTPIN (-6000 5625) BN 3
J 2
(-5988 5633);
DISPLAY 0.489362 (-5988 5633);
PAINT GREEN (-5988 5633);
FORCEPROP 2 LAST CDS_LIB mstr_standard
J 2
(-6050 5625);
DISPLAY 0.723404 (-6050 5625);
PAINT MONO (-6050 5625);
DISPLAY INVISIBLE (-6050 5625);
FORCEPROP 1 LAST BODY_TYPE PLUMBING
J 2
(-6050 5675);
DISPLAY 0.872340 (-6050 5675);
PAINT GREEN (-6050 5675);
DISPLAY INVISIBLE (-6050 5675);
FORCEPROP 1 LAST HDL_TAP TRUE
J 2
(-6375 5500);
DISPLAY 0.872340 (-6375 5500);
DISPLAY INVISIBLE (-6375 5500);
FORCEPROP 1 LAST PATH I256
J 2
(-6048 5625);
DISPLAY 0.872340 (-6048 5625);
PAINT GREEN (-6048 5625);
DISPLAY INVISIBLE (-6048 5625);
FORCEADD TAP..1
R 2
(-6050 5525);
FORCEPROP 3 LASTPIN (-6000 5525) SIG_NAME M_E_CPU1_SA_DQS_DN<4>
J 0
(-5990 5535);
DISPLAY 0.659574 (-5990 5535);
PAINT MONO (-5990 5535);
DISPLAY INVISIBLE (-5990 5535);
FORCEPROP 1 LASTPIN (-6000 5525) BN 4
J 2
(-5988 5533);
DISPLAY 0.489362 (-5988 5533);
PAINT GREEN (-5988 5533);
FORCEPROP 2 LAST CDS_LIB mstr_standard
J 2
(-6050 5525);
DISPLAY 0.723404 (-6050 5525);
PAINT MONO (-6050 5525);
DISPLAY INVISIBLE (-6050 5525);
FORCEPROP 1 LAST BODY_TYPE PLUMBING
J 2
(-6050 5575);
DISPLAY 0.872340 (-6050 5575);
PAINT GREEN (-6050 5575);
DISPLAY INVISIBLE (-6050 5575);
FORCEPROP 1 LAST HDL_TAP TRUE
J 2
(-6375 5400);
DISPLAY 0.872340 (-6375 5400);
DISPLAY INVISIBLE (-6375 5400);
FORCEPROP 1 LAST PATH I257
J 2
(-6048 5525);
DISPLAY 0.872340 (-6048 5525);
PAINT GREEN (-6048 5525);
DISPLAY INVISIBLE (-6048 5525);
FORCEADD TAP..1
R 2
(-6050 5425);
FORCEPROP 3 LASTPIN (-6000 5425) SIG_NAME M_E_CPU1_SA_DQS_DN<5>
J 0
(-5990 5435);
DISPLAY 0.659574 (-5990 5435);
PAINT MONO (-5990 5435);
DISPLAY INVISIBLE (-5990 5435);
FORCEPROP 1 LASTPIN (-6000 5425) BN 5
J 2
(-5988 5433);
DISPLAY 0.489362 (-5988 5433);
PAINT GREEN (-5988 5433);
FORCEPROP 2 LAST CDS_LIB mstr_standard
J 2
(-6050 5425);
DISPLAY 0.723404 (-6050 5425);
PAINT MONO (-6050 5425);
DISPLAY INVISIBLE (-6050 5425);
FORCEPROP 1 LAST BODY_TYPE PLUMBING
J 2
(-6050 5475);
DISPLAY 0.872340 (-6050 5475);
PAINT GREEN (-6050 5475);
DISPLAY INVISIBLE (-6050 5475);
FORCEPROP 1 LAST HDL_TAP TRUE
J 2
(-6375 5300);
DISPLAY 0.872340 (-6375 5300);
DISPLAY INVISIBLE (-6375 5300);
FORCEPROP 1 LAST PATH I258
J 2
(-6048 5425);
DISPLAY 0.872340 (-6048 5425);
PAINT GREEN (-6048 5425);
DISPLAY INVISIBLE (-6048 5425);
FORCEADD TAP..1
R 2
(-6050 5325);
FORCEPROP 3 LASTPIN (-6000 5325) SIG_NAME M_E_CPU1_SA_DQS_DN<6>
J 0
(-5990 5335);
DISPLAY 0.659574 (-5990 5335);
PAINT MONO (-5990 5335);
DISPLAY INVISIBLE (-5990 5335);
FORCEPROP 1 LASTPIN (-6000 5325) BN 6
J 2
(-5988 5333);
DISPLAY 0.489362 (-5988 5333);
PAINT GREEN (-5988 5333);
FORCEPROP 2 LAST CDS_LIB mstr_standard
J 2
(-6050 5325);
DISPLAY 0.723404 (-6050 5325);
PAINT MONO (-6050 5325);
DISPLAY INVISIBLE (-6050 5325);
FORCEPROP 1 LAST BODY_TYPE PLUMBING
J 2
(-6050 5375);
DISPLAY 0.872340 (-6050 5375);
PAINT GREEN (-6050 5375);
DISPLAY INVISIBLE (-6050 5375);
FORCEPROP 1 LAST HDL_TAP TRUE
J 2
(-6375 5200);
DISPLAY 0.872340 (-6375 5200);
DISPLAY INVISIBLE (-6375 5200);
FORCEPROP 1 LAST PATH I259
J 2
(-6048 5325);
DISPLAY 0.872340 (-6048 5325);
PAINT GREEN (-6048 5325);
DISPLAY INVISIBLE (-6048 5325);
FORCEADD TAP..1
R 2
(-6050 5125);
FORCEPROP 3 LASTPIN (-6000 5125) SIG_NAME M_E_CPU1_SA_DQS_DN<8>
J 0
(-5990 5135);
DISPLAY 0.659574 (-5990 5135);
PAINT MONO (-5990 5135);
DISPLAY INVISIBLE (-5990 5135);
FORCEPROP 1 LASTPIN (-6000 5125) BN 8
J 2
(-5988 5133);
DISPLAY 0.489362 (-5988 5133);
PAINT GREEN (-5988 5133);
FORCEPROP 2 LAST CDS_LIB mstr_standard
J 2
(-6050 5125);
DISPLAY 0.723404 (-6050 5125);
PAINT MONO (-6050 5125);
DISPLAY INVISIBLE (-6050 5125);
FORCEPROP 1 LAST BODY_TYPE PLUMBING
J 2
(-6050 5175);
DISPLAY 0.872340 (-6050 5175);
PAINT GREEN (-6050 5175);
DISPLAY INVISIBLE (-6050 5175);
FORCEPROP 1 LAST HDL_TAP TRUE
J 2
(-6375 5000);
DISPLAY 0.872340 (-6375 5000);
DISPLAY INVISIBLE (-6375 5000);
FORCEPROP 1 LAST PATH I260
J 2
(-6048 5125);
DISPLAY 0.872340 (-6048 5125);
PAINT GREEN (-6048 5125);
DISPLAY INVISIBLE (-6048 5125);
FORCEADD TAP..1
R 2
(-6050 5225);
FORCEPROP 3 LASTPIN (-6000 5225) SIG_NAME M_E_CPU1_SA_DQS_DN<7>
J 0
(-5990 5235);
DISPLAY 0.659574 (-5990 5235);
PAINT MONO (-5990 5235);
DISPLAY INVISIBLE (-5990 5235);
FORCEPROP 1 LASTPIN (-6000 5225) BN 7
J 2
(-5988 5233);
DISPLAY 0.489362 (-5988 5233);
PAINT GREEN (-5988 5233);
FORCEPROP 2 LAST CDS_LIB mstr_standard
J 2
(-6050 5225);
DISPLAY 0.723404 (-6050 5225);
PAINT MONO (-6050 5225);
DISPLAY INVISIBLE (-6050 5225);
FORCEPROP 1 LAST BODY_TYPE PLUMBING
J 2
(-6050 5275);
DISPLAY 0.872340 (-6050 5275);
PAINT GREEN (-6050 5275);
DISPLAY INVISIBLE (-6050 5275);
FORCEPROP 1 LAST HDL_TAP TRUE
J 2
(-6375 5100);
DISPLAY 0.872340 (-6375 5100);
DISPLAY INVISIBLE (-6375 5100);
FORCEPROP 1 LAST PATH I261
J 2
(-6048 5225);
DISPLAY 0.872340 (-6048 5225);
PAINT GREEN (-6048 5225);
DISPLAY INVISIBLE (-6048 5225);
FORCEADD TAP..1
R 2
(-5850 4925);
FORCEPROP 3 LASTPIN (-5800 4925) SIG_NAME M_E_CPU1_SB_DQS_DP<0>
J 0
(-5790 4935);
DISPLAY 0.659574 (-5790 4935);
PAINT MONO (-5790 4935);
DISPLAY INVISIBLE (-5790 4935);
FORCEPROP 1 LASTPIN (-5800 4925) BN 0
J 2
(-5788 4933);
DISPLAY 0.489362 (-5788 4933);
PAINT GREEN (-5788 4933);
FORCEPROP 2 LAST CDS_LIB mstr_standard
J 2
(-5850 4925);
DISPLAY 0.723404 (-5850 4925);
PAINT MONO (-5850 4925);
DISPLAY INVISIBLE (-5850 4925);
FORCEPROP 1 LAST BODY_TYPE PLUMBING
J 2
(-5850 4975);
DISPLAY 0.872340 (-5850 4975);
PAINT GREEN (-5850 4975);
DISPLAY INVISIBLE (-5850 4975);
FORCEPROP 1 LAST HDL_TAP TRUE
J 2
(-6175 4800);
DISPLAY 0.872340 (-6175 4800);
DISPLAY INVISIBLE (-6175 4800);
FORCEPROP 1 LAST PATH I262
J 2
(-5848 4925);
DISPLAY 0.872340 (-5848 4925);
PAINT GREEN (-5848 4925);
DISPLAY INVISIBLE (-5848 4925);
FORCEADD TAP..1
R 2
(-5850 5075);
FORCEPROP 3 LASTPIN (-5800 5075) SIG_NAME M_E_CPU1_SA_DQS_DP<9>
J 0
(-5790 5085);
DISPLAY 0.659574 (-5790 5085);
PAINT MONO (-5790 5085);
DISPLAY INVISIBLE (-5790 5085);
FORCEPROP 1 LASTPIN (-5800 5075) BN 9
J 2
(-5788 5083);
DISPLAY 0.489362 (-5788 5083);
PAINT GREEN (-5788 5083);
FORCEPROP 2 LAST CDS_LIB mstr_standard
J 2
(-5850 5075);
DISPLAY 0.723404 (-5850 5075);
PAINT MONO (-5850 5075);
DISPLAY INVISIBLE (-5850 5075);
FORCEPROP 1 LAST BODY_TYPE PLUMBING
J 2
(-5850 5125);
DISPLAY 0.872340 (-5850 5125);
PAINT GREEN (-5850 5125);
DISPLAY INVISIBLE (-5850 5125);
FORCEPROP 1 LAST HDL_TAP TRUE
J 2
(-6175 4950);
DISPLAY 0.872340 (-6175 4950);
DISPLAY INVISIBLE (-6175 4950);
FORCEPROP 1 LAST PATH I263
J 2
(-5848 5075);
DISPLAY 0.872340 (-5848 5075);
PAINT GREEN (-5848 5075);
DISPLAY INVISIBLE (-5848 5075);
FORCEADD TAP..1
R 2
(-5850 4825);
FORCEPROP 3 LASTPIN (-5800 4825) SIG_NAME M_E_CPU1_SB_DQS_DP<1>
J 0
(-5790 4835);
DISPLAY 0.659574 (-5790 4835);
PAINT MONO (-5790 4835);
DISPLAY INVISIBLE (-5790 4835);
FORCEPROP 1 LASTPIN (-5800 4825) BN 1
J 2
(-5788 4833);
DISPLAY 0.489362 (-5788 4833);
PAINT GREEN (-5788 4833);
FORCEPROP 2 LAST CDS_LIB mstr_standard
J 2
(-5850 4825);
DISPLAY 0.723404 (-5850 4825);
PAINT MONO (-5850 4825);
DISPLAY INVISIBLE (-5850 4825);
FORCEPROP 1 LAST BODY_TYPE PLUMBING
J 2
(-5850 4875);
DISPLAY 0.872340 (-5850 4875);
PAINT GREEN (-5850 4875);
DISPLAY INVISIBLE (-5850 4875);
FORCEPROP 1 LAST HDL_TAP TRUE
J 2
(-6175 4700);
DISPLAY 0.872340 (-6175 4700);
DISPLAY INVISIBLE (-6175 4700);
FORCEPROP 1 LAST PATH I264
J 2
(-5848 4825);
DISPLAY 0.872340 (-5848 4825);
PAINT GREEN (-5848 4825);
DISPLAY INVISIBLE (-5848 4825);
FORCEADD TAP..1
R 2
(-5850 4725);
FORCEPROP 3 LASTPIN (-5800 4725) SIG_NAME M_E_CPU1_SB_DQS_DP<2>
J 0
(-5790 4735);
DISPLAY 0.659574 (-5790 4735);
PAINT MONO (-5790 4735);
DISPLAY INVISIBLE (-5790 4735);
FORCEPROP 1 LASTPIN (-5800 4725) BN 2
J 2
(-5788 4733);
DISPLAY 0.489362 (-5788 4733);
PAINT GREEN (-5788 4733);
FORCEPROP 2 LAST CDS_LIB mstr_standard
J 2
(-5850 4725);
DISPLAY 0.723404 (-5850 4725);
PAINT MONO (-5850 4725);
DISPLAY INVISIBLE (-5850 4725);
FORCEPROP 1 LAST BODY_TYPE PLUMBING
J 2
(-5850 4775);
DISPLAY 0.872340 (-5850 4775);
PAINT GREEN (-5850 4775);
DISPLAY INVISIBLE (-5850 4775);
FORCEPROP 1 LAST HDL_TAP TRUE
J 2
(-6175 4600);
DISPLAY 0.872340 (-6175 4600);
DISPLAY INVISIBLE (-6175 4600);
FORCEPROP 1 LAST PATH I265
J 2
(-5848 4725);
DISPLAY 0.872340 (-5848 4725);
PAINT GREEN (-5848 4725);
DISPLAY INVISIBLE (-5848 4725);
FORCEADD TAP..1
R 2
(-5850 4625);
FORCEPROP 3 LASTPIN (-5800 4625) SIG_NAME M_E_CPU1_SB_DQS_DP<3>
J 0
(-5790 4635);
DISPLAY 0.659574 (-5790 4635);
PAINT MONO (-5790 4635);
DISPLAY INVISIBLE (-5790 4635);
FORCEPROP 1 LASTPIN (-5800 4625) BN 3
J 2
(-5788 4633);
DISPLAY 0.489362 (-5788 4633);
PAINT GREEN (-5788 4633);
FORCEPROP 2 LAST CDS_LIB mstr_standard
J 2
(-5850 4625);
DISPLAY 0.723404 (-5850 4625);
PAINT MONO (-5850 4625);
DISPLAY INVISIBLE (-5850 4625);
FORCEPROP 1 LAST BODY_TYPE PLUMBING
J 2
(-5850 4675);
DISPLAY 0.872340 (-5850 4675);
PAINT GREEN (-5850 4675);
DISPLAY INVISIBLE (-5850 4675);
FORCEPROP 1 LAST HDL_TAP TRUE
J 2
(-6175 4500);
DISPLAY 0.872340 (-6175 4500);
DISPLAY INVISIBLE (-6175 4500);
FORCEPROP 1 LAST PATH I266
J 2
(-5848 4625);
DISPLAY 0.872340 (-5848 4625);
PAINT GREEN (-5848 4625);
DISPLAY INVISIBLE (-5848 4625);
FORCEADD TAP..1
R 2
(-6050 5025);
FORCEPROP 3 LASTPIN (-6000 5025) SIG_NAME M_E_CPU1_SA_DQS_DN<9>
J 0
(-5990 5035);
DISPLAY 0.659574 (-5990 5035);
PAINT MONO (-5990 5035);
DISPLAY INVISIBLE (-5990 5035);
FORCEPROP 1 LASTPIN (-6000 5025) BN 9
J 2
(-5988 5033);
DISPLAY 0.489362 (-5988 5033);
PAINT GREEN (-5988 5033);
FORCEPROP 2 LAST CDS_LIB mstr_standard
J 2
(-6050 5025);
DISPLAY 0.723404 (-6050 5025);
PAINT MONO (-6050 5025);
DISPLAY INVISIBLE (-6050 5025);
FORCEPROP 1 LAST BODY_TYPE PLUMBING
J 2
(-6050 5075);
DISPLAY 0.872340 (-6050 5075);
PAINT GREEN (-6050 5075);
DISPLAY INVISIBLE (-6050 5075);
FORCEPROP 1 LAST HDL_TAP TRUE
J 2
(-6375 4900);
DISPLAY 0.872340 (-6375 4900);
DISPLAY INVISIBLE (-6375 4900);
FORCEPROP 1 LAST PATH I267
J 2
(-6048 5025);
DISPLAY 0.872340 (-6048 5025);
PAINT GREEN (-6048 5025);
DISPLAY INVISIBLE (-6048 5025);
FORCEADD TAP..1
R 2
(-6050 4875);
FORCEPROP 3 LASTPIN (-6000 4875) SIG_NAME M_E_CPU1_SB_DQS_DN<0>
J 0
(-5990 4885);
DISPLAY 0.659574 (-5990 4885);
PAINT MONO (-5990 4885);
DISPLAY INVISIBLE (-5990 4885);
FORCEPROP 1 LASTPIN (-6000 4875) BN 0
J 2
(-5988 4883);
DISPLAY 0.489362 (-5988 4883);
PAINT GREEN (-5988 4883);
FORCEPROP 2 LAST CDS_LIB mstr_standard
J 2
(-6050 4875);
DISPLAY 0.723404 (-6050 4875);
PAINT MONO (-6050 4875);
DISPLAY INVISIBLE (-6050 4875);
FORCEPROP 1 LAST BODY_TYPE PLUMBING
J 2
(-6050 4925);
DISPLAY 0.872340 (-6050 4925);
PAINT GREEN (-6050 4925);
DISPLAY INVISIBLE (-6050 4925);
FORCEPROP 1 LAST HDL_TAP TRUE
J 2
(-6375 4750);
DISPLAY 0.872340 (-6375 4750);
DISPLAY INVISIBLE (-6375 4750);
FORCEPROP 1 LAST PATH I268
J 2
(-6048 4875);
DISPLAY 0.872340 (-6048 4875);
PAINT GREEN (-6048 4875);
DISPLAY INVISIBLE (-6048 4875);
FORCEADD TAP..1
R 2
(-6050 4775);
FORCEPROP 3 LASTPIN (-6000 4775) SIG_NAME M_E_CPU1_SB_DQS_DN<1>
J 0
(-5990 4785);
DISPLAY 0.659574 (-5990 4785);
PAINT MONO (-5990 4785);
DISPLAY INVISIBLE (-5990 4785);
FORCEPROP 1 LASTPIN (-6000 4775) BN 1
J 2
(-5988 4783);
DISPLAY 0.489362 (-5988 4783);
PAINT GREEN (-5988 4783);
FORCEPROP 2 LAST CDS_LIB mstr_standard
J 2
(-6050 4775);
DISPLAY 0.723404 (-6050 4775);
PAINT MONO (-6050 4775);
DISPLAY INVISIBLE (-6050 4775);
FORCEPROP 1 LAST BODY_TYPE PLUMBING
J 2
(-6050 4825);
DISPLAY 0.872340 (-6050 4825);
PAINT GREEN (-6050 4825);
DISPLAY INVISIBLE (-6050 4825);
FORCEPROP 1 LAST HDL_TAP TRUE
J 2
(-6375 4650);
DISPLAY 0.872340 (-6375 4650);
DISPLAY INVISIBLE (-6375 4650);
FORCEPROP 1 LAST PATH I269
J 2
(-6048 4775);
DISPLAY 0.872340 (-6048 4775);
PAINT GREEN (-6048 4775);
DISPLAY INVISIBLE (-6048 4775);
FORCEADD TAP..1
R 2
(-6050 4675);
FORCEPROP 3 LASTPIN (-6000 4675) SIG_NAME M_E_CPU1_SB_DQS_DN<2>
J 0
(-5990 4685);
DISPLAY 0.659574 (-5990 4685);
PAINT MONO (-5990 4685);
DISPLAY INVISIBLE (-5990 4685);
FORCEPROP 1 LASTPIN (-6000 4675) BN 2
J 2
(-5988 4683);
DISPLAY 0.489362 (-5988 4683);
PAINT GREEN (-5988 4683);
FORCEPROP 2 LAST CDS_LIB mstr_standard
J 2
(-6050 4675);
DISPLAY 0.723404 (-6050 4675);
PAINT MONO (-6050 4675);
DISPLAY INVISIBLE (-6050 4675);
FORCEPROP 1 LAST BODY_TYPE PLUMBING
J 2
(-6050 4725);
DISPLAY 0.872340 (-6050 4725);
PAINT GREEN (-6050 4725);
DISPLAY INVISIBLE (-6050 4725);
FORCEPROP 1 LAST HDL_TAP TRUE
J 2
(-6375 4550);
DISPLAY 0.872340 (-6375 4550);
DISPLAY INVISIBLE (-6375 4550);
FORCEPROP 1 LAST PATH I270
J 2
(-6048 4675);
DISPLAY 0.872340 (-6048 4675);
PAINT GREEN (-6048 4675);
DISPLAY INVISIBLE (-6048 4675);
FORCEADD TAP..1
R 2
(-5850 4425);
FORCEPROP 3 LASTPIN (-5800 4425) SIG_NAME M_E_CPU1_SB_DQS_DP<5>
J 0
(-5790 4435);
DISPLAY 0.659574 (-5790 4435);
PAINT MONO (-5790 4435);
DISPLAY INVISIBLE (-5790 4435);
FORCEPROP 1 LASTPIN (-5800 4425) BN 5
J 2
(-5788 4433);
DISPLAY 0.489362 (-5788 4433);
PAINT GREEN (-5788 4433);
FORCEPROP 2 LAST CDS_LIB mstr_standard
J 2
(-5850 4425);
DISPLAY 0.723404 (-5850 4425);
PAINT MONO (-5850 4425);
DISPLAY INVISIBLE (-5850 4425);
FORCEPROP 1 LAST BODY_TYPE PLUMBING
J 2
(-5850 4475);
DISPLAY 0.872340 (-5850 4475);
PAINT GREEN (-5850 4475);
DISPLAY INVISIBLE (-5850 4475);
FORCEPROP 1 LAST HDL_TAP TRUE
J 2
(-6175 4300);
DISPLAY 0.872340 (-6175 4300);
DISPLAY INVISIBLE (-6175 4300);
FORCEPROP 1 LAST PATH I271
J 2
(-5848 4425);
DISPLAY 0.872340 (-5848 4425);
PAINT GREEN (-5848 4425);
DISPLAY INVISIBLE (-5848 4425);
FORCEADD TAP..1
R 2
(-5850 4525);
FORCEPROP 3 LASTPIN (-5800 4525) SIG_NAME M_E_CPU1_SB_DQS_DP<4>
J 0
(-5790 4535);
DISPLAY 0.659574 (-5790 4535);
PAINT MONO (-5790 4535);
DISPLAY INVISIBLE (-5790 4535);
FORCEPROP 1 LASTPIN (-5800 4525) BN 4
J 2
(-5788 4533);
DISPLAY 0.489362 (-5788 4533);
PAINT GREEN (-5788 4533);
FORCEPROP 2 LAST CDS_LIB mstr_standard
J 2
(-5850 4525);
DISPLAY 0.723404 (-5850 4525);
PAINT MONO (-5850 4525);
DISPLAY INVISIBLE (-5850 4525);
FORCEPROP 1 LAST BODY_TYPE PLUMBING
J 2
(-5850 4575);
DISPLAY 0.872340 (-5850 4575);
PAINT GREEN (-5850 4575);
DISPLAY INVISIBLE (-5850 4575);
FORCEPROP 1 LAST HDL_TAP TRUE
J 2
(-6175 4400);
DISPLAY 0.872340 (-6175 4400);
DISPLAY INVISIBLE (-6175 4400);
FORCEPROP 1 LAST PATH I272
J 2
(-5848 4525);
DISPLAY 0.872340 (-5848 4525);
PAINT GREEN (-5848 4525);
DISPLAY INVISIBLE (-5848 4525);
FORCEADD TAP..1
R 2
(-5850 4325);
FORCEPROP 3 LASTPIN (-5800 4325) SIG_NAME M_E_CPU1_SB_DQS_DP<6>
J 0
(-5790 4335);
DISPLAY 0.659574 (-5790 4335);
PAINT MONO (-5790 4335);
DISPLAY INVISIBLE (-5790 4335);
FORCEPROP 1 LASTPIN (-5800 4325) BN 6
J 2
(-5788 4333);
DISPLAY 0.489362 (-5788 4333);
PAINT GREEN (-5788 4333);
FORCEPROP 2 LAST CDS_LIB mstr_standard
J 2
(-5850 4325);
DISPLAY 0.723404 (-5850 4325);
PAINT MONO (-5850 4325);
DISPLAY INVISIBLE (-5850 4325);
FORCEPROP 1 LAST BODY_TYPE PLUMBING
J 2
(-5850 4375);
DISPLAY 0.872340 (-5850 4375);
PAINT GREEN (-5850 4375);
DISPLAY INVISIBLE (-5850 4375);
FORCEPROP 1 LAST HDL_TAP TRUE
J 2
(-6175 4200);
DISPLAY 0.872340 (-6175 4200);
DISPLAY INVISIBLE (-6175 4200);
FORCEPROP 1 LAST PATH I273
J 2
(-5848 4325);
DISPLAY 0.872340 (-5848 4325);
PAINT GREEN (-5848 4325);
DISPLAY INVISIBLE (-5848 4325);
FORCEADD TAP..1
R 2
(-5850 4125);
FORCEPROP 3 LASTPIN (-5800 4125) SIG_NAME M_E_CPU1_SB_DQS_DP<8>
J 0
(-5790 4135);
DISPLAY 0.659574 (-5790 4135);
PAINT MONO (-5790 4135);
DISPLAY INVISIBLE (-5790 4135);
FORCEPROP 1 LASTPIN (-5800 4125) BN 8
J 2
(-5788 4133);
DISPLAY 0.489362 (-5788 4133);
PAINT GREEN (-5788 4133);
FORCEPROP 2 LAST CDS_LIB mstr_standard
J 2
(-5850 4125);
DISPLAY 0.723404 (-5850 4125);
PAINT MONO (-5850 4125);
DISPLAY INVISIBLE (-5850 4125);
FORCEPROP 1 LAST BODY_TYPE PLUMBING
J 2
(-5850 4175);
DISPLAY 0.872340 (-5850 4175);
PAINT GREEN (-5850 4175);
DISPLAY INVISIBLE (-5850 4175);
FORCEPROP 1 LAST HDL_TAP TRUE
J 2
(-6175 4000);
DISPLAY 0.872340 (-6175 4000);
DISPLAY INVISIBLE (-6175 4000);
FORCEPROP 1 LAST PATH I274
J 2
(-5848 4125);
DISPLAY 0.872340 (-5848 4125);
PAINT GREEN (-5848 4125);
DISPLAY INVISIBLE (-5848 4125);
FORCEADD TAP..1
R 2
(-5850 4225);
FORCEPROP 3 LASTPIN (-5800 4225) SIG_NAME M_E_CPU1_SB_DQS_DP<7>
J 0
(-5790 4235);
DISPLAY 0.659574 (-5790 4235);
PAINT MONO (-5790 4235);
DISPLAY INVISIBLE (-5790 4235);
FORCEPROP 1 LASTPIN (-5800 4225) BN 7
J 2
(-5788 4233);
DISPLAY 0.489362 (-5788 4233);
PAINT GREEN (-5788 4233);
FORCEPROP 2 LAST CDS_LIB mstr_standard
J 2
(-5850 4225);
DISPLAY 0.723404 (-5850 4225);
PAINT MONO (-5850 4225);
DISPLAY INVISIBLE (-5850 4225);
FORCEPROP 1 LAST BODY_TYPE PLUMBING
J 2
(-5850 4275);
DISPLAY 0.872340 (-5850 4275);
PAINT GREEN (-5850 4275);
DISPLAY INVISIBLE (-5850 4275);
FORCEPROP 1 LAST HDL_TAP TRUE
J 2
(-6175 4100);
DISPLAY 0.872340 (-6175 4100);
DISPLAY INVISIBLE (-6175 4100);
FORCEPROP 1 LAST PATH I275
J 2
(-5848 4225);
DISPLAY 0.872340 (-5848 4225);
PAINT GREEN (-5848 4225);
DISPLAY INVISIBLE (-5848 4225);
FORCEADD TAP..1
R 2
(-6050 4575);
FORCEPROP 3 LASTPIN (-6000 4575) SIG_NAME M_E_CPU1_SB_DQS_DN<3>
J 0
(-5990 4585);
DISPLAY 0.659574 (-5990 4585);
PAINT MONO (-5990 4585);
DISPLAY INVISIBLE (-5990 4585);
FORCEPROP 1 LASTPIN (-6000 4575) BN 3
J 2
(-5988 4583);
DISPLAY 0.489362 (-5988 4583);
PAINT GREEN (-5988 4583);
FORCEPROP 2 LAST CDS_LIB mstr_standard
J 2
(-6050 4575);
DISPLAY 0.723404 (-6050 4575);
PAINT MONO (-6050 4575);
DISPLAY INVISIBLE (-6050 4575);
FORCEPROP 1 LAST BODY_TYPE PLUMBING
J 2
(-6050 4625);
DISPLAY 0.872340 (-6050 4625);
PAINT GREEN (-6050 4625);
DISPLAY INVISIBLE (-6050 4625);
FORCEPROP 1 LAST HDL_TAP TRUE
J 2
(-6375 4450);
DISPLAY 0.872340 (-6375 4450);
DISPLAY INVISIBLE (-6375 4450);
FORCEPROP 1 LAST PATH I276
J 2
(-6048 4575);
DISPLAY 0.872340 (-6048 4575);
PAINT GREEN (-6048 4575);
DISPLAY INVISIBLE (-6048 4575);
FORCEADD TAP..1
R 2
(-6050 4475);
FORCEPROP 3 LASTPIN (-6000 4475) SIG_NAME M_E_CPU1_SB_DQS_DN<4>
J 0
(-5990 4485);
DISPLAY 0.659574 (-5990 4485);
PAINT MONO (-5990 4485);
DISPLAY INVISIBLE (-5990 4485);
FORCEPROP 1 LASTPIN (-6000 4475) BN 4
J 2
(-5988 4483);
DISPLAY 0.489362 (-5988 4483);
PAINT GREEN (-5988 4483);
FORCEPROP 2 LAST CDS_LIB mstr_standard
J 2
(-6050 4475);
DISPLAY 0.723404 (-6050 4475);
PAINT MONO (-6050 4475);
DISPLAY INVISIBLE (-6050 4475);
FORCEPROP 1 LAST BODY_TYPE PLUMBING
J 2
(-6050 4525);
DISPLAY 0.872340 (-6050 4525);
PAINT GREEN (-6050 4525);
DISPLAY INVISIBLE (-6050 4525);
FORCEPROP 1 LAST HDL_TAP TRUE
J 2
(-6375 4350);
DISPLAY 0.872340 (-6375 4350);
DISPLAY INVISIBLE (-6375 4350);
FORCEPROP 1 LAST PATH I277
J 2
(-6048 4475);
DISPLAY 0.872340 (-6048 4475);
PAINT GREEN (-6048 4475);
DISPLAY INVISIBLE (-6048 4475);
FORCEADD TAP..1
R 2
(-6050 4375);
FORCEPROP 3 LASTPIN (-6000 4375) SIG_NAME M_E_CPU1_SB_DQS_DN<5>
J 0
(-5990 4385);
DISPLAY 0.659574 (-5990 4385);
PAINT MONO (-5990 4385);
DISPLAY INVISIBLE (-5990 4385);
FORCEPROP 1 LASTPIN (-6000 4375) BN 5
J 2
(-5988 4383);
DISPLAY 0.489362 (-5988 4383);
PAINT GREEN (-5988 4383);
FORCEPROP 2 LAST CDS_LIB mstr_standard
J 2
(-6050 4375);
DISPLAY 0.723404 (-6050 4375);
PAINT MONO (-6050 4375);
DISPLAY INVISIBLE (-6050 4375);
FORCEPROP 1 LAST BODY_TYPE PLUMBING
J 2
(-6050 4425);
DISPLAY 0.872340 (-6050 4425);
PAINT GREEN (-6050 4425);
DISPLAY INVISIBLE (-6050 4425);
FORCEPROP 1 LAST HDL_TAP TRUE
J 2
(-6375 4250);
DISPLAY 0.872340 (-6375 4250);
DISPLAY INVISIBLE (-6375 4250);
FORCEPROP 1 LAST PATH I278
J 2
(-6048 4375);
DISPLAY 0.872340 (-6048 4375);
PAINT GREEN (-6048 4375);
DISPLAY INVISIBLE (-6048 4375);
FORCEADD TAP..1
R 2
(-6050 4275);
FORCEPROP 3 LASTPIN (-6000 4275) SIG_NAME M_E_CPU1_SB_DQS_DN<6>
J 0
(-5990 4285);
DISPLAY 0.659574 (-5990 4285);
PAINT MONO (-5990 4285);
DISPLAY INVISIBLE (-5990 4285);
FORCEPROP 1 LASTPIN (-6000 4275) BN 6
J 2
(-5988 4283);
DISPLAY 0.489362 (-5988 4283);
PAINT GREEN (-5988 4283);
FORCEPROP 2 LAST CDS_LIB mstr_standard
J 2
(-6050 4275);
DISPLAY 0.723404 (-6050 4275);
PAINT MONO (-6050 4275);
DISPLAY INVISIBLE (-6050 4275);
FORCEPROP 1 LAST BODY_TYPE PLUMBING
J 2
(-6050 4325);
DISPLAY 0.872340 (-6050 4325);
PAINT GREEN (-6050 4325);
DISPLAY INVISIBLE (-6050 4325);
FORCEPROP 1 LAST HDL_TAP TRUE
J 2
(-6375 4150);
DISPLAY 0.872340 (-6375 4150);
DISPLAY INVISIBLE (-6375 4150);
FORCEPROP 1 LAST PATH I279
J 2
(-6048 4275);
DISPLAY 0.872340 (-6048 4275);
PAINT GREEN (-6048 4275);
DISPLAY INVISIBLE (-6048 4275);
FORCEADD TAP..1
R 2
(-6050 4175);
FORCEPROP 3 LASTPIN (-6000 4175) SIG_NAME M_E_CPU1_SB_DQS_DN<7>
J 0
(-5990 4185);
DISPLAY 0.659574 (-5990 4185);
PAINT MONO (-5990 4185);
DISPLAY INVISIBLE (-5990 4185);
FORCEPROP 1 LASTPIN (-6000 4175) BN 7
J 2
(-5988 4183);
DISPLAY 0.489362 (-5988 4183);
PAINT GREEN (-5988 4183);
FORCEPROP 2 LAST CDS_LIB mstr_standard
J 2
(-6050 4175);
DISPLAY 0.723404 (-6050 4175);
PAINT MONO (-6050 4175);
DISPLAY INVISIBLE (-6050 4175);
FORCEPROP 1 LAST BODY_TYPE PLUMBING
J 2
(-6050 4225);
DISPLAY 0.872340 (-6050 4225);
PAINT GREEN (-6050 4225);
DISPLAY INVISIBLE (-6050 4225);
FORCEPROP 1 LAST HDL_TAP TRUE
J 2
(-6375 4050);
DISPLAY 0.872340 (-6375 4050);
DISPLAY INVISIBLE (-6375 4050);
FORCEPROP 1 LAST PATH I280
J 2
(-6048 4175);
DISPLAY 0.872340 (-6048 4175);
PAINT GREEN (-6048 4175);
DISPLAY INVISIBLE (-6048 4175);
FORCEADD OFFPAGE..3
R 2
(-6750 5950);
FORCEPROP 2 LAST $XR0 102 
J 0
(-7030 5950);
DISPLAY 0.638298 (-7030 5950);
PAINT MONO (-7030 5950);
FORCEPROP 2 LAST CDS_LIB standard
J 0
(-6750 5950);
DISPLAY INVISIBLE (-6750 5950);
FORCEPROP 1 LAST OFFPAGE TRUE
J 2
(-7075 5825);
DISPLAY 0.872340 (-7075 5825);
PAINT GREEN (-7075 5825);
DISPLAY INVISIBLE (-7075 5825);
FORCEPROP 1 LAST COMMENT_BODY TRUE
J 2
(-6700 5850);
DISPLAY 0.872340 (-6700 5850);
PAINT GREEN (-6700 5850);
DISPLAY INVISIBLE (-6700 5850);
FORCEPROP 2 LAST PATH I281
J 0
(-7025 6000);
DISPLAY 1.021277 (-7025 6000);
DISPLAY INVISIBLE (-7025 6000);
FORCEADD OFFPAGE..3
R 2
(-6750 6000);
FORCEPROP 2 LAST $XR0 102 
J 0
(-7030 6000);
DISPLAY 0.638298 (-7030 6000);
PAINT MONO (-7030 6000);
FORCEPROP 2 LAST CDS_LIB standard
J 0
(-6750 6000);
DISPLAY INVISIBLE (-6750 6000);
FORCEPROP 1 LAST OFFPAGE TRUE
J 2
(-7075 5875);
DISPLAY 0.872340 (-7075 5875);
PAINT GREEN (-7075 5875);
DISPLAY INVISIBLE (-7075 5875);
FORCEPROP 1 LAST COMMENT_BODY TRUE
J 2
(-6700 5900);
DISPLAY 0.872340 (-6700 5900);
PAINT GREEN (-6700 5900);
DISPLAY INVISIBLE (-6700 5900);
FORCEPROP 2 LAST PATH I282
J 0
(-7025 6050);
DISPLAY 1.021277 (-7025 6050);
DISPLAY INVISIBLE (-7025 6050);
FORCEADD OFFPAGE..3
R 2
(-6750 4900);
FORCEPROP 2 LAST $XR0 102 
J 0
(-7030 4900);
DISPLAY 0.638298 (-7030 4900);
PAINT MONO (-7030 4900);
FORCEPROP 2 LAST CDS_LIB standard
J 0
(-6750 4900);
DISPLAY INVISIBLE (-6750 4900);
FORCEPROP 1 LAST OFFPAGE TRUE
J 2
(-7075 4775);
DISPLAY 0.872340 (-7075 4775);
PAINT GREEN (-7075 4775);
DISPLAY INVISIBLE (-7075 4775);
FORCEPROP 1 LAST COMMENT_BODY TRUE
J 2
(-6700 4800);
DISPLAY 0.872340 (-6700 4800);
PAINT GREEN (-6700 4800);
DISPLAY INVISIBLE (-6700 4800);
FORCEPROP 2 LAST PATH I283
J 0
(-7025 4950);
DISPLAY 1.021277 (-7025 4950);
DISPLAY INVISIBLE (-7025 4950);
FORCEADD OFFPAGE..3
R 2
(-6750 4950);
FORCEPROP 2 LAST $XR0 102 
J 0
(-7030 4950);
DISPLAY 0.638298 (-7030 4950);
PAINT MONO (-7030 4950);
FORCEPROP 2 LAST CDS_LIB standard
J 0
(-6750 4950);
DISPLAY INVISIBLE (-6750 4950);
FORCEPROP 1 LAST OFFPAGE TRUE
J 2
(-7075 4825);
DISPLAY 0.872340 (-7075 4825);
PAINT GREEN (-7075 4825);
DISPLAY INVISIBLE (-7075 4825);
FORCEPROP 1 LAST COMMENT_BODY TRUE
J 2
(-6700 4850);
DISPLAY 0.872340 (-6700 4850);
PAINT GREEN (-6700 4850);
DISPLAY INVISIBLE (-6700 4850);
FORCEPROP 2 LAST PATH I284
J 0
(-7025 5000);
DISPLAY 1.021277 (-7025 5000);
DISPLAY INVISIBLE (-7025 5000);
FORCEADD TAP..1
R 2
(-5850 4025);
FORCEPROP 3 LASTPIN (-5800 4025) SIG_NAME M_E_CPU1_SB_DQS_DP<9>
J 0
(-5790 4035);
DISPLAY 0.659574 (-5790 4035);
PAINT MONO (-5790 4035);
DISPLAY INVISIBLE (-5790 4035);
FORCEPROP 1 LASTPIN (-5800 4025) BN 9
J 2
(-5788 4033);
DISPLAY 0.489362 (-5788 4033);
PAINT GREEN (-5788 4033);
FORCEPROP 2 LAST CDS_LIB mstr_standard
J 2
(-5850 4025);
DISPLAY 0.723404 (-5850 4025);
PAINT MONO (-5850 4025);
DISPLAY INVISIBLE (-5850 4025);
FORCEPROP 1 LAST BODY_TYPE PLUMBING
J 2
(-5850 4075);
DISPLAY 0.872340 (-5850 4075);
PAINT GREEN (-5850 4075);
DISPLAY INVISIBLE (-5850 4075);
FORCEPROP 1 LAST HDL_TAP TRUE
J 2
(-6175 3900);
DISPLAY 0.872340 (-6175 3900);
DISPLAY INVISIBLE (-6175 3900);
FORCEPROP 1 LAST PATH I285
J 2
(-5848 4025);
DISPLAY 0.872340 (-5848 4025);
PAINT GREEN (-5848 4025);
DISPLAY INVISIBLE (-5848 4025);
FORCEADD TAP..1
R 2
(-6050 4075);
FORCEPROP 3 LASTPIN (-6000 4075) SIG_NAME M_E_CPU1_SB_DQS_DN<8>
J 0
(-5990 4085);
DISPLAY 0.659574 (-5990 4085);
PAINT MONO (-5990 4085);
DISPLAY INVISIBLE (-5990 4085);
FORCEPROP 1 LASTPIN (-6000 4075) BN 8
J 2
(-5988 4083);
DISPLAY 0.489362 (-5988 4083);
PAINT GREEN (-5988 4083);
FORCEPROP 2 LAST CDS_LIB mstr_standard
J 2
(-6050 4075);
DISPLAY 0.723404 (-6050 4075);
PAINT MONO (-6050 4075);
DISPLAY INVISIBLE (-6050 4075);
FORCEPROP 1 LAST BODY_TYPE PLUMBING
J 2
(-6050 4125);
DISPLAY 0.872340 (-6050 4125);
PAINT GREEN (-6050 4125);
DISPLAY INVISIBLE (-6050 4125);
FORCEPROP 1 LAST HDL_TAP TRUE
J 2
(-6375 3950);
DISPLAY 0.872340 (-6375 3950);
DISPLAY INVISIBLE (-6375 3950);
FORCEPROP 1 LAST PATH I286
J 2
(-6048 4075);
DISPLAY 0.872340 (-6048 4075);
PAINT GREEN (-6048 4075);
DISPLAY INVISIBLE (-6048 4075);
FORCEADD TAP..1
R 2
(-6050 3975);
FORCEPROP 3 LASTPIN (-6000 3975) SIG_NAME M_E_CPU1_SB_DQS_DN<9>
J 0
(-5990 3985);
DISPLAY 0.659574 (-5990 3985);
PAINT MONO (-5990 3985);
DISPLAY INVISIBLE (-5990 3985);
FORCEPROP 1 LASTPIN (-6000 3975) BN 9
J 2
(-5988 3983);
DISPLAY 0.489362 (-5988 3983);
PAINT GREEN (-5988 3983);
FORCEPROP 2 LAST CDS_LIB mstr_standard
J 2
(-6050 3975);
DISPLAY 0.723404 (-6050 3975);
PAINT MONO (-6050 3975);
DISPLAY INVISIBLE (-6050 3975);
FORCEPROP 1 LAST BODY_TYPE PLUMBING
J 2
(-6050 4025);
DISPLAY 0.872340 (-6050 4025);
PAINT GREEN (-6050 4025);
DISPLAY INVISIBLE (-6050 4025);
FORCEPROP 1 LAST HDL_TAP TRUE
J 2
(-6375 3850);
DISPLAY 0.872340 (-6375 3850);
DISPLAY INVISIBLE (-6375 3850);
FORCEPROP 1 LAST PATH I287
J 2
(-6048 3975);
DISPLAY 0.872340 (-6048 3975);
PAINT GREEN (-6048 3975);
DISPLAY INVISIBLE (-6048 3975);
FORCEADD TAP..1
R 2
(-6050 3825);
FORCEPROP 3 LASTPIN (-6000 3825) SIG_NAME M_E_CPU1_SA_CA<0>
J 0
(-5990 3835);
DISPLAY 0.659574 (-5990 3835);
PAINT MONO (-5990 3835);
DISPLAY INVISIBLE (-5990 3835);
FORCEPROP 1 LASTPIN (-6000 3825) BN 0
J 2
(-5988 3833);
DISPLAY 0.489362 (-5988 3833);
PAINT GREEN (-5988 3833);
FORCEPROP 2 LAST CDS_LIB mstr_standard
J 0
(-6050 3825);
DISPLAY 0.723404 (-6050 3825);
PAINT MONO (-6050 3825);
DISPLAY INVISIBLE (-6050 3825);
FORCEPROP 1 LAST BODY_TYPE PLUMBING
J 2
(-6050 3875);
DISPLAY 0.872340 (-6050 3875);
PAINT GREEN (-6050 3875);
DISPLAY INVISIBLE (-6050 3875);
FORCEPROP 1 LAST HDL_TAP TRUE
J 2
(-6375 3700);
DISPLAY 0.872340 (-6375 3700);
DISPLAY INVISIBLE (-6375 3700);
FORCEPROP 1 LAST PATH I288
J 2
(-6048 3825);
DISPLAY 0.872340 (-6048 3825);
PAINT GREEN (-6048 3825);
DISPLAY INVISIBLE (-6048 3825);
FORCEADD TAP..1
R 2
(-6050 3775);
FORCEPROP 3 LASTPIN (-6000 3775) SIG_NAME M_E_CPU1_SA_CA<1>
J 0
(-5990 3785);
DISPLAY 0.659574 (-5990 3785);
PAINT MONO (-5990 3785);
DISPLAY INVISIBLE (-5990 3785);
FORCEPROP 1 LASTPIN (-6000 3775) BN 1
J 2
(-5988 3783);
DISPLAY 0.489362 (-5988 3783);
PAINT GREEN (-5988 3783);
FORCEPROP 2 LAST CDS_LIB mstr_standard
J 0
(-6050 3775);
DISPLAY 0.723404 (-6050 3775);
PAINT MONO (-6050 3775);
DISPLAY INVISIBLE (-6050 3775);
FORCEPROP 1 LAST BODY_TYPE PLUMBING
J 2
(-6050 3825);
DISPLAY 0.872340 (-6050 3825);
PAINT GREEN (-6050 3825);
DISPLAY INVISIBLE (-6050 3825);
FORCEPROP 1 LAST HDL_TAP TRUE
J 2
(-6375 3650);
DISPLAY 0.872340 (-6375 3650);
DISPLAY INVISIBLE (-6375 3650);
FORCEPROP 1 LAST PATH I289
J 2
(-6048 3775);
DISPLAY 0.872340 (-6048 3775);
PAINT GREEN (-6048 3775);
DISPLAY INVISIBLE (-6048 3775);
FORCEADD TAP..1
R 2
(-6050 3725);
FORCEPROP 3 LASTPIN (-6000 3725) SIG_NAME M_E_CPU1_SA_CA<2>
J 0
(-5990 3735);
DISPLAY 0.659574 (-5990 3735);
PAINT MONO (-5990 3735);
DISPLAY INVISIBLE (-5990 3735);
FORCEPROP 1 LASTPIN (-6000 3725) BN 2
J 2
(-5988 3733);
DISPLAY 0.489362 (-5988 3733);
PAINT GREEN (-5988 3733);
FORCEPROP 2 LAST CDS_LIB mstr_standard
J 0
(-6050 3725);
DISPLAY 0.723404 (-6050 3725);
PAINT MONO (-6050 3725);
DISPLAY INVISIBLE (-6050 3725);
FORCEPROP 1 LAST BODY_TYPE PLUMBING
J 2
(-6050 3775);
DISPLAY 0.872340 (-6050 3775);
PAINT GREEN (-6050 3775);
DISPLAY INVISIBLE (-6050 3775);
FORCEPROP 1 LAST HDL_TAP TRUE
J 2
(-6375 3600);
DISPLAY 0.872340 (-6375 3600);
DISPLAY INVISIBLE (-6375 3600);
FORCEPROP 1 LAST PATH I290
J 2
(-6048 3725);
DISPLAY 0.872340 (-6048 3725);
PAINT GREEN (-6048 3725);
DISPLAY INVISIBLE (-6048 3725);
FORCEADD TAP..1
R 2
(-6050 3675);
FORCEPROP 3 LASTPIN (-6000 3675) SIG_NAME M_E_CPU1_SA_CA<3>
J 0
(-5990 3685);
DISPLAY 0.659574 (-5990 3685);
PAINT MONO (-5990 3685);
DISPLAY INVISIBLE (-5990 3685);
FORCEPROP 1 LASTPIN (-6000 3675) BN 3
J 2
(-5988 3683);
DISPLAY 0.489362 (-5988 3683);
PAINT GREEN (-5988 3683);
FORCEPROP 2 LAST CDS_LIB mstr_standard
J 0
(-6050 3675);
DISPLAY 0.723404 (-6050 3675);
PAINT MONO (-6050 3675);
DISPLAY INVISIBLE (-6050 3675);
FORCEPROP 1 LAST BODY_TYPE PLUMBING
J 2
(-6050 3725);
DISPLAY 0.872340 (-6050 3725);
PAINT GREEN (-6050 3725);
DISPLAY INVISIBLE (-6050 3725);
FORCEPROP 1 LAST HDL_TAP TRUE
J 2
(-6375 3550);
DISPLAY 0.872340 (-6375 3550);
DISPLAY INVISIBLE (-6375 3550);
FORCEPROP 1 LAST PATH I291
J 2
(-6048 3675);
DISPLAY 0.872340 (-6048 3675);
PAINT GREEN (-6048 3675);
DISPLAY INVISIBLE (-6048 3675);
FORCEADD TAP..1
R 2
(-6050 3625);
FORCEPROP 3 LASTPIN (-6000 3625) SIG_NAME M_E_CPU1_SA_CA<4>
J 0
(-5990 3635);
DISPLAY 0.659574 (-5990 3635);
PAINT MONO (-5990 3635);
DISPLAY INVISIBLE (-5990 3635);
FORCEPROP 1 LASTPIN (-6000 3625) BN 4
J 2
(-5988 3633);
DISPLAY 0.489362 (-5988 3633);
PAINT GREEN (-5988 3633);
FORCEPROP 2 LAST CDS_LIB mstr_standard
J 0
(-6050 3625);
DISPLAY 0.723404 (-6050 3625);
PAINT MONO (-6050 3625);
DISPLAY INVISIBLE (-6050 3625);
FORCEPROP 1 LAST BODY_TYPE PLUMBING
J 2
(-6050 3675);
DISPLAY 0.872340 (-6050 3675);
PAINT GREEN (-6050 3675);
DISPLAY INVISIBLE (-6050 3675);
FORCEPROP 1 LAST HDL_TAP TRUE
J 2
(-6375 3500);
DISPLAY 0.872340 (-6375 3500);
DISPLAY INVISIBLE (-6375 3500);
FORCEPROP 1 LAST PATH I292
J 2
(-6048 3625);
DISPLAY 0.872340 (-6048 3625);
PAINT GREEN (-6048 3625);
DISPLAY INVISIBLE (-6048 3625);
FORCEADD TAP..1
R 2
(-6050 3575);
FORCEPROP 3 LASTPIN (-6000 3575) SIG_NAME M_E_CPU1_SA_CA<5>
J 0
(-5990 3585);
DISPLAY 0.659574 (-5990 3585);
PAINT MONO (-5990 3585);
DISPLAY INVISIBLE (-5990 3585);
FORCEPROP 1 LASTPIN (-6000 3575) BN 5
J 2
(-5988 3583);
DISPLAY 0.489362 (-5988 3583);
PAINT GREEN (-5988 3583);
FORCEPROP 2 LAST CDS_LIB mstr_standard
J 0
(-6050 3575);
DISPLAY 0.723404 (-6050 3575);
PAINT MONO (-6050 3575);
DISPLAY INVISIBLE (-6050 3575);
FORCEPROP 1 LAST BODY_TYPE PLUMBING
J 2
(-6050 3625);
DISPLAY 0.872340 (-6050 3625);
PAINT GREEN (-6050 3625);
DISPLAY INVISIBLE (-6050 3625);
FORCEPROP 1 LAST HDL_TAP TRUE
J 2
(-6375 3450);
DISPLAY 0.872340 (-6375 3450);
DISPLAY INVISIBLE (-6375 3450);
FORCEPROP 1 LAST PATH I293
J 2
(-6048 3575);
DISPLAY 0.872340 (-6048 3575);
PAINT GREEN (-6048 3575);
DISPLAY INVISIBLE (-6048 3575);
FORCEADD TAP..1
R 2
(-6050 3525);
FORCEPROP 3 LASTPIN (-6000 3525) SIG_NAME M_E_CPU1_SA_CA<6>
J 0
(-5990 3535);
DISPLAY 0.659574 (-5990 3535);
PAINT MONO (-5990 3535);
DISPLAY INVISIBLE (-5990 3535);
FORCEPROP 1 LASTPIN (-6000 3525) BN 6
J 2
(-5988 3533);
DISPLAY 0.489362 (-5988 3533);
PAINT GREEN (-5988 3533);
FORCEPROP 2 LAST CDS_LIB mstr_standard
J 0
(-6050 3525);
DISPLAY 0.723404 (-6050 3525);
PAINT MONO (-6050 3525);
DISPLAY INVISIBLE (-6050 3525);
FORCEPROP 1 LAST BODY_TYPE PLUMBING
J 2
(-6050 3575);
DISPLAY 0.872340 (-6050 3575);
PAINT GREEN (-6050 3575);
DISPLAY INVISIBLE (-6050 3575);
FORCEPROP 1 LAST HDL_TAP TRUE
J 2
(-6375 3400);
DISPLAY 0.872340 (-6375 3400);
DISPLAY INVISIBLE (-6375 3400);
FORCEPROP 1 LAST PATH I294
J 2
(-6048 3525);
DISPLAY 0.872340 (-6048 3525);
PAINT GREEN (-6048 3525);
DISPLAY INVISIBLE (-6048 3525);
FORCEADD TAP..1
R 2
(-6050 3425);
FORCEPROP 3 LASTPIN (-6000 3425) SIG_NAME M_E_CPU1_SB_CA<0>
J 0
(-5990 3435);
DISPLAY 0.659574 (-5990 3435);
PAINT MONO (-5990 3435);
DISPLAY INVISIBLE (-5990 3435);
FORCEPROP 1 LASTPIN (-6000 3425) BN 0
J 2
(-5988 3433);
DISPLAY 0.489362 (-5988 3433);
PAINT GREEN (-5988 3433);
FORCEPROP 2 LAST CDS_LIB mstr_standard
J 0
(-6050 3425);
DISPLAY 0.723404 (-6050 3425);
PAINT MONO (-6050 3425);
DISPLAY INVISIBLE (-6050 3425);
FORCEPROP 1 LAST BODY_TYPE PLUMBING
J 2
(-6050 3475);
DISPLAY 0.872340 (-6050 3475);
PAINT GREEN (-6050 3475);
DISPLAY INVISIBLE (-6050 3475);
FORCEPROP 1 LAST HDL_TAP TRUE
J 2
(-6375 3300);
DISPLAY 0.872340 (-6375 3300);
DISPLAY INVISIBLE (-6375 3300);
FORCEPROP 1 LAST PATH I295
J 2
(-6048 3425);
DISPLAY 0.872340 (-6048 3425);
PAINT GREEN (-6048 3425);
DISPLAY INVISIBLE (-6048 3425);
FORCEADD TAP..1
R 2
(-6050 3375);
FORCEPROP 3 LASTPIN (-6000 3375) SIG_NAME M_E_CPU1_SB_CA<1>
J 0
(-5990 3385);
DISPLAY 0.659574 (-5990 3385);
PAINT MONO (-5990 3385);
DISPLAY INVISIBLE (-5990 3385);
FORCEPROP 1 LASTPIN (-6000 3375) BN 1
J 2
(-5988 3383);
DISPLAY 0.489362 (-5988 3383);
PAINT GREEN (-5988 3383);
FORCEPROP 2 LAST CDS_LIB mstr_standard
J 0
(-6050 3375);
DISPLAY 0.723404 (-6050 3375);
PAINT MONO (-6050 3375);
DISPLAY INVISIBLE (-6050 3375);
FORCEPROP 1 LAST BODY_TYPE PLUMBING
J 2
(-6050 3425);
DISPLAY 0.872340 (-6050 3425);
PAINT GREEN (-6050 3425);
DISPLAY INVISIBLE (-6050 3425);
FORCEPROP 1 LAST HDL_TAP TRUE
J 2
(-6375 3250);
DISPLAY 0.872340 (-6375 3250);
DISPLAY INVISIBLE (-6375 3250);
FORCEPROP 1 LAST PATH I296
J 2
(-6048 3375);
DISPLAY 0.872340 (-6048 3375);
PAINT GREEN (-6048 3375);
DISPLAY INVISIBLE (-6048 3375);
FORCEADD TAP..1
R 2
(-6050 3325);
FORCEPROP 3 LASTPIN (-6000 3325) SIG_NAME M_E_CPU1_SB_CA<2>
J 0
(-5990 3335);
DISPLAY 0.659574 (-5990 3335);
PAINT MONO (-5990 3335);
DISPLAY INVISIBLE (-5990 3335);
FORCEPROP 1 LASTPIN (-6000 3325) BN 2
J 2
(-5988 3333);
DISPLAY 0.489362 (-5988 3333);
PAINT GREEN (-5988 3333);
FORCEPROP 2 LAST CDS_LIB mstr_standard
J 0
(-6050 3325);
DISPLAY 0.723404 (-6050 3325);
PAINT MONO (-6050 3325);
DISPLAY INVISIBLE (-6050 3325);
FORCEPROP 1 LAST BODY_TYPE PLUMBING
J 2
(-6050 3375);
DISPLAY 0.872340 (-6050 3375);
PAINT GREEN (-6050 3375);
DISPLAY INVISIBLE (-6050 3375);
FORCEPROP 1 LAST HDL_TAP TRUE
J 2
(-6375 3200);
DISPLAY 0.872340 (-6375 3200);
DISPLAY INVISIBLE (-6375 3200);
FORCEPROP 1 LAST PATH I297
J 2
(-6048 3325);
DISPLAY 0.872340 (-6048 3325);
PAINT GREEN (-6048 3325);
DISPLAY INVISIBLE (-6048 3325);
FORCEADD TAP..1
R 2
(-6050 3275);
FORCEPROP 3 LASTPIN (-6000 3275) SIG_NAME M_E_CPU1_SB_CA<3>
J 0
(-5990 3285);
DISPLAY 0.659574 (-5990 3285);
PAINT MONO (-5990 3285);
DISPLAY INVISIBLE (-5990 3285);
FORCEPROP 1 LASTPIN (-6000 3275) BN 3
J 2
(-5988 3283);
DISPLAY 0.489362 (-5988 3283);
PAINT GREEN (-5988 3283);
FORCEPROP 2 LAST CDS_LIB mstr_standard
J 0
(-6050 3275);
DISPLAY 0.723404 (-6050 3275);
PAINT MONO (-6050 3275);
DISPLAY INVISIBLE (-6050 3275);
FORCEPROP 1 LAST BODY_TYPE PLUMBING
J 2
(-6050 3325);
DISPLAY 0.872340 (-6050 3325);
PAINT GREEN (-6050 3325);
DISPLAY INVISIBLE (-6050 3325);
FORCEPROP 1 LAST HDL_TAP TRUE
J 2
(-6375 3150);
DISPLAY 0.872340 (-6375 3150);
DISPLAY INVISIBLE (-6375 3150);
FORCEPROP 1 LAST PATH I298
J 2
(-6048 3275);
DISPLAY 0.872340 (-6048 3275);
PAINT GREEN (-6048 3275);
DISPLAY INVISIBLE (-6048 3275);
FORCEADD TAP..1
R 2
(-6050 3225);
FORCEPROP 3 LASTPIN (-6000 3225) SIG_NAME M_E_CPU1_SB_CA<4>
J 0
(-5990 3235);
DISPLAY 0.659574 (-5990 3235);
PAINT MONO (-5990 3235);
DISPLAY INVISIBLE (-5990 3235);
FORCEPROP 1 LASTPIN (-6000 3225) BN 4
J 2
(-5988 3233);
DISPLAY 0.489362 (-5988 3233);
PAINT GREEN (-5988 3233);
FORCEPROP 2 LAST CDS_LIB mstr_standard
J 0
(-6050 3225);
DISPLAY 0.723404 (-6050 3225);
PAINT MONO (-6050 3225);
DISPLAY INVISIBLE (-6050 3225);
FORCEPROP 1 LAST BODY_TYPE PLUMBING
J 2
(-6050 3275);
DISPLAY 0.872340 (-6050 3275);
PAINT GREEN (-6050 3275);
DISPLAY INVISIBLE (-6050 3275);
FORCEPROP 1 LAST HDL_TAP TRUE
J 2
(-6375 3100);
DISPLAY 0.872340 (-6375 3100);
DISPLAY INVISIBLE (-6375 3100);
FORCEPROP 1 LAST PATH I299
J 2
(-6048 3225);
DISPLAY 0.872340 (-6048 3225);
PAINT GREEN (-6048 3225);
DISPLAY INVISIBLE (-6048 3225);
FORCEADD TAP..1
R 2
(-6050 3125);
FORCEPROP 3 LASTPIN (-6000 3125) SIG_NAME M_E_CPU1_SB_CA<6>
J 0
(-5990 3135);
DISPLAY 0.659574 (-5990 3135);
PAINT MONO (-5990 3135);
DISPLAY INVISIBLE (-5990 3135);
FORCEPROP 1 LASTPIN (-6000 3125) BN 6
J 2
(-5988 3133);
DISPLAY 0.489362 (-5988 3133);
PAINT GREEN (-5988 3133);
FORCEPROP 2 LAST CDS_LIB mstr_standard
J 0
(-6050 3125);
DISPLAY 0.723404 (-6050 3125);
PAINT MONO (-6050 3125);
DISPLAY INVISIBLE (-6050 3125);
FORCEPROP 1 LAST BODY_TYPE PLUMBING
J 2
(-6050 3175);
DISPLAY 0.872340 (-6050 3175);
PAINT GREEN (-6050 3175);
DISPLAY INVISIBLE (-6050 3175);
FORCEPROP 1 LAST HDL_TAP TRUE
J 2
(-6375 3000);
DISPLAY 0.872340 (-6375 3000);
DISPLAY INVISIBLE (-6375 3000);
FORCEPROP 1 LAST PATH I300
J 2
(-6048 3125);
DISPLAY 0.872340 (-6048 3125);
PAINT GREEN (-6048 3125);
DISPLAY INVISIBLE (-6048 3125);
FORCEADD TAP..1
R 2
(-6050 3175);
FORCEPROP 3 LASTPIN (-6000 3175) SIG_NAME M_E_CPU1_SB_CA<5>
J 0
(-5990 3185);
DISPLAY 0.659574 (-5990 3185);
PAINT MONO (-5990 3185);
DISPLAY INVISIBLE (-5990 3185);
FORCEPROP 1 LASTPIN (-6000 3175) BN 5
J 2
(-5988 3183);
DISPLAY 0.489362 (-5988 3183);
PAINT GREEN (-5988 3183);
FORCEPROP 2 LAST CDS_LIB mstr_standard
J 0
(-6050 3175);
DISPLAY 0.723404 (-6050 3175);
PAINT MONO (-6050 3175);
DISPLAY INVISIBLE (-6050 3175);
FORCEPROP 1 LAST BODY_TYPE PLUMBING
J 2
(-6050 3225);
DISPLAY 0.872340 (-6050 3225);
PAINT GREEN (-6050 3225);
DISPLAY INVISIBLE (-6050 3225);
FORCEPROP 1 LAST HDL_TAP TRUE
J 2
(-6375 3050);
DISPLAY 0.872340 (-6375 3050);
DISPLAY INVISIBLE (-6375 3050);
FORCEPROP 1 LAST PATH I301
J 2
(-6048 3175);
DISPLAY 0.872340 (-6048 3175);
PAINT GREEN (-6048 3175);
DISPLAY INVISIBLE (-6048 3175);
FORCEADD OFFPAGE..2
R 2
(-6650 3850);
FORCEPROP 2 LAST $XR0 102 
J 0
(-6905 3850);
DISPLAY 0.638298 (-6905 3850);
PAINT MONO (-6905 3850);
FORCEPROP 2 LAST CDS_LIB standard
J 0
(-6650 3850);
DISPLAY INVISIBLE (-6650 3850);
FORCEPROP 1 LAST OFFPAGE TRUE
J 2
(-6975 3725);
DISPLAY 0.872340 (-6975 3725);
PAINT GREEN (-6975 3725);
DISPLAY INVISIBLE (-6975 3725);
FORCEPROP 1 LAST COMMENT_BODY TRUE
J 2
(-6605 3755);
DISPLAY 0.872340 (-6605 3755);
PAINT GREEN (-6605 3755);
DISPLAY INVISIBLE (-6605 3755);
FORCEPROP 2 LAST PATH I302
J 0
(-6900 3900);
DISPLAY 1.021277 (-6900 3900);
DISPLAY INVISIBLE (-6900 3900);
FORCEADD OFFPAGE..2
R 2
(-6650 3450);
FORCEPROP 2 LAST $XR0 102 
J 0
(-6905 3450);
DISPLAY 0.638298 (-6905 3450);
PAINT MONO (-6905 3450);
FORCEPROP 2 LAST CDS_LIB standard
J 0
(-6650 3450);
DISPLAY INVISIBLE (-6650 3450);
FORCEPROP 1 LAST OFFPAGE TRUE
J 2
(-6975 3325);
DISPLAY 0.872340 (-6975 3325);
PAINT GREEN (-6975 3325);
DISPLAY INVISIBLE (-6975 3325);
FORCEPROP 1 LAST COMMENT_BODY TRUE
J 2
(-6605 3355);
DISPLAY 0.872340 (-6605 3355);
PAINT GREEN (-6605 3355);
DISPLAY INVISIBLE (-6605 3355);
FORCEPROP 2 LAST PATH I303
J 0
(-6900 3500);
DISPLAY 1.021277 (-6900 3500);
DISPLAY INVISIBLE (-6900 3500);
FORCEADD OFFPAGE..2
R 2
(-6650 2975);
FORCEPROP 2 LAST $XR0 102 
J 0
(-6905 2975);
DISPLAY 0.638298 (-6905 2975);
PAINT MONO (-6905 2975);
FORCEPROP 2 LAST CDS_LIB standard
J 0
(-6650 2975);
DISPLAY INVISIBLE (-6650 2975);
FORCEPROP 1 LAST OFFPAGE TRUE
J 2
(-6975 2850);
DISPLAY 0.872340 (-6975 2850);
PAINT GREEN (-6975 2850);
DISPLAY INVISIBLE (-6975 2850);
FORCEPROP 1 LAST COMMENT_BODY TRUE
J 2
(-6605 2880);
DISPLAY 0.872340 (-6605 2880);
PAINT GREEN (-6605 2880);
DISPLAY INVISIBLE (-6605 2880);
FORCEPROP 2 LAST PATH I304
J 0
(-6900 3025);
DISPLAY 1.021277 (-6900 3025);
DISPLAY INVISIBLE (-6900 3025);
FORCEADD OFFPAGE..2
R 2
(-6650 2925);
FORCEPROP 2 LAST $XR0 102 
J 0
(-6905 2925);
DISPLAY 0.638298 (-6905 2925);
PAINT MONO (-6905 2925);
FORCEPROP 2 LAST CDS_LIB standard
J 0
(-6650 2925);
DISPLAY INVISIBLE (-6650 2925);
FORCEPROP 1 LAST OFFPAGE TRUE
J 2
(-6975 2800);
DISPLAY 0.872340 (-6975 2800);
PAINT GREEN (-6975 2800);
DISPLAY INVISIBLE (-6975 2800);
FORCEPROP 1 LAST COMMENT_BODY TRUE
J 2
(-6605 2830);
DISPLAY 0.872340 (-6605 2830);
PAINT GREEN (-6605 2830);
DISPLAY INVISIBLE (-6605 2830);
FORCEPROP 2 LAST PATH I305
J 0
(-6900 2975);
DISPLAY 1.021277 (-6900 2975);
DISPLAY INVISIBLE (-6900 2975);
FORCEADD OFFPAGE..2
R 2
(-6650 2825);
FORCEPROP 2 LAST $XR0 102 
J 0
(-6905 2825);
DISPLAY 0.638298 (-6905 2825);
PAINT MONO (-6905 2825);
FORCEPROP 2 LAST CDS_LIB standard
J 0
(-6650 2825);
DISPLAY INVISIBLE (-6650 2825);
FORCEPROP 1 LAST OFFPAGE TRUE
J 2
(-6975 2700);
DISPLAY 0.872340 (-6975 2700);
PAINT GREEN (-6975 2700);
DISPLAY INVISIBLE (-6975 2700);
FORCEPROP 1 LAST COMMENT_BODY TRUE
J 2
(-6605 2730);
DISPLAY 0.872340 (-6605 2730);
PAINT GREEN (-6605 2730);
DISPLAY INVISIBLE (-6605 2730);
FORCEPROP 2 LAST PATH I306
J 0
(-6900 2875);
DISPLAY 1.021277 (-6900 2875);
DISPLAY INVISIBLE (-6900 2875);
FORCEADD OFFPAGE..1
(-6650 2675);
FORCEPROP 2 LAST $XR0 102 
J 0
(-6902 2675);
DISPLAY 0.638298 (-6902 2675);
PAINT MONO (-6902 2675);
FORCEPROP 2 LAST CDS_LIB standard
J 0
(-6650 2675);
DISPLAY INVISIBLE (-6650 2675);
FORCEPROP 1 LAST OFFPAGE TRUE
J 0
(-6325 2550);
DISPLAY 0.872340 (-6325 2550);
PAINT GREEN (-6325 2550);
DISPLAY INVISIBLE (-6325 2550);
FORCEPROP 1 LAST COMMENT_BODY TRUE
J 0
(-6525 2575);
DISPLAY 0.872340 (-6525 2575);
PAINT GREEN (-6525 2575);
DISPLAY INVISIBLE (-6525 2575);
FORCEPROP 2 LAST PATH I307
J 0
(-6925 2725);
DISPLAY 1.021277 (-6925 2725);
DISPLAY INVISIBLE (-6925 2725);
FORCEADD OFFPAGE..2
R 2
(-6650 2775);
FORCEPROP 2 LAST $XR0 102 
J 0
(-6905 2775);
DISPLAY 0.638298 (-6905 2775);
PAINT MONO (-6905 2775);
FORCEPROP 2 LAST CDS_LIB standard
J 0
(-6650 2775);
DISPLAY INVISIBLE (-6650 2775);
FORCEPROP 1 LAST OFFPAGE TRUE
J 2
(-6975 2650);
DISPLAY 0.872340 (-6975 2650);
PAINT GREEN (-6975 2650);
DISPLAY INVISIBLE (-6975 2650);
FORCEPROP 1 LAST COMMENT_BODY TRUE
J 2
(-6605 2680);
DISPLAY 0.872340 (-6605 2680);
PAINT GREEN (-6605 2680);
DISPLAY INVISIBLE (-6605 2680);
FORCEPROP 2 LAST PATH I308
J 0
(-6900 2825);
DISPLAY 1.021277 (-6900 2825);
DISPLAY INVISIBLE (-6900 2825);
FORCEADD OFFPAGE..5
(-6650 2575);
FORCEPROP 2 LAST $XR0 102 
J 0
(-6905 2575);
DISPLAY 0.638298 (-6905 2575);
PAINT MONO (-6905 2575);
FORCEPROP 2 LAST CDS_LIB mstr_standard
J 0
(-6650 2575);
DISPLAY INVISIBLE (-6650 2575);
FORCEPROP 1 LAST OFFPAGE TRUE
J 0
(-6325 2450);
DISPLAY 0.872340 (-6325 2450);
PAINT GREEN (-6325 2450);
DISPLAY INVISIBLE (-6325 2450);
FORCEPROP 1 LAST COMMENT_BODY TRUE
J 0
(-6550 2500);
DISPLAY 0.872340 (-6550 2500);
PAINT GREEN (-6550 2500);
DISPLAY INVISIBLE (-6550 2500);
FORCEPROP 2 LAST PATH I309
J 0
(-6900 2625);
DISPLAY 1.021277 (-6900 2625);
DISPLAY INVISIBLE (-6900 2625);
FORCEADD OFFPAGE..2
R 2
(-6650 2425);
FORCEPROP 2 LAST $XR0 102 
J 0
(-6905 2425);
DISPLAY 0.638298 (-6905 2425);
PAINT MONO (-6905 2425);
FORCEPROP 2 LAST CDS_LIB standard
J 0
(-6650 2425);
DISPLAY INVISIBLE (-6650 2425);
FORCEPROP 1 LAST OFFPAGE TRUE
J 2
(-6975 2300);
DISPLAY 0.872340 (-6975 2300);
PAINT GREEN (-6975 2300);
DISPLAY INVISIBLE (-6975 2300);
FORCEPROP 1 LAST COMMENT_BODY TRUE
J 2
(-6605 2330);
DISPLAY 0.872340 (-6605 2330);
PAINT GREEN (-6605 2330);
DISPLAY INVISIBLE (-6605 2330);
FORCEPROP 2 LAST PATH I310
J 0
(-6900 2475);
DISPLAY 1.021277 (-6900 2475);
DISPLAY INVISIBLE (-6900 2475);
FORCEADD OFFPAGE..2
R 2
(-6650 2475);
FORCEPROP 2 LAST $XR0 102 
J 0
(-6905 2475);
DISPLAY 0.638298 (-6905 2475);
PAINT MONO (-6905 2475);
FORCEPROP 2 LAST CDS_LIB standard
J 0
(-6650 2475);
DISPLAY INVISIBLE (-6650 2475);
FORCEPROP 1 LAST OFFPAGE TRUE
J 2
(-6975 2350);
DISPLAY 0.872340 (-6975 2350);
PAINT GREEN (-6975 2350);
DISPLAY INVISIBLE (-6975 2350);
FORCEPROP 1 LAST COMMENT_BODY TRUE
J 2
(-6605 2380);
DISPLAY 0.872340 (-6605 2380);
PAINT GREEN (-6605 2380);
DISPLAY INVISIBLE (-6605 2380);
FORCEPROP 2 LAST PATH I311
J 0
(-6900 2525);
DISPLAY 1.021277 (-6900 2525);
DISPLAY INVISIBLE (-6900 2525);
FORCEADD OFFPAGE..1
(-6650 2325);
FORCEPROP 2 LAST $XR0 102 
J 0
(-6902 2325);
DISPLAY 0.638298 (-6902 2325);
PAINT MONO (-6902 2325);
FORCEPROP 2 LAST CDS_LIB standard
J 0
(-6650 2325);
DISPLAY INVISIBLE (-6650 2325);
FORCEPROP 1 LAST OFFPAGE TRUE
J 0
(-6325 2200);
DISPLAY 0.872340 (-6325 2200);
PAINT GREEN (-6325 2200);
DISPLAY INVISIBLE (-6325 2200);
FORCEPROP 1 LAST COMMENT_BODY TRUE
J 0
(-6525 2225);
DISPLAY 0.872340 (-6525 2225);
PAINT GREEN (-6525 2225);
DISPLAY INVISIBLE (-6525 2225);
FORCEPROP 2 LAST PATH I312
J 0
(-6925 2375);
DISPLAY 1.021277 (-6925 2375);
DISPLAY INVISIBLE (-6925 2375);
FORCEADD OFFPAGE..5
(-6650 2225);
FORCEPROP 2 LAST $XR0 102 
J 0
(-6905 2225);
DISPLAY 0.638298 (-6905 2225);
PAINT MONO (-6905 2225);
FORCEPROP 2 LAST CDS_LIB standard
J 0
(-6650 2225);
DISPLAY INVISIBLE (-6650 2225);
FORCEPROP 1 LAST OFFPAGE TRUE
J 0
(-6325 2100);
DISPLAY 0.872340 (-6325 2100);
PAINT GREEN (-6325 2100);
DISPLAY INVISIBLE (-6325 2100);
FORCEPROP 1 LAST COMMENT_BODY TRUE
J 0
(-6550 2150);
DISPLAY 0.872340 (-6550 2150);
PAINT GREEN (-6550 2150);
DISPLAY INVISIBLE (-6550 2150);
FORCEPROP 2 LAST PATH I313
J 0
(-6900 2275);
DISPLAY 1.021277 (-6900 2275);
DISPLAY INVISIBLE (-6900 2275);
FORCEADD Q_RES..1
(-6725 2125);
FORCEPROP 1 LAST LOCATION R504
J 0
(-7050 2125);
DISPLAY 0.489362 (-7050 2125);
PAINT SKYBLUE (-7050 2125);
FORCEPROP 0 LAST $SEC 1
J 0
(-6900 2175);
DISPLAY 0.680851 (-6900 2175);
PAINT MONO (-6900 2175);
DISPLAY INVISIBLE (-6900 2175);
FORCEPROP 0 LAST CDS_SEC 1
J 0
(-6900 2175);
DISPLAY 1.021277 (-6900 2175);
DISPLAY INVISIBLE (-6900 2175);
FORCEPROP 1 LASTPIN (-6825 2125) $PN 1
J 0
(-6813 2137);
DISPLAY 0.489362 (-6813 2137);
PAINT MONO (-6813 2137);
FORCEPROP 1 LASTPIN (-6625 2125) $PN 2
J 0
(-6663 2137);
DISPLAY 0.489362 (-6663 2137);
PAINT MONO (-6663 2137);
FORCEPROP 1 LAST PACK_TYPE 0402LF
J 0
(-7050 2100);
DISPLAY 0.489362 (-7050 2100);
PAINT SKYBLUE (-7050 2100);
FORCEPROP 1 LAST TOLERANCE 1%
J 0
(-6450 2125);
DISPLAY 0.489362 (-6450 2125);
PAINT SKYBLUE (-6450 2125);
FORCEPROP 1 LAST VALUE 15
J 2
(-6400 2125);
DISPLAY 0.489362 (-6400 2125);
PAINT SKYBLUE (-6400 2125);
FORCEPROP 1 LAST MATERIAL CHIP
J 0
(-6850 2250);
DISPLAY 0.638298 (-6850 2250);
PAINT SKYBLUE (-6850 2250);
DISPLAY INVISIBLE (-6850 2250);
FORCEPROP 1 LAST WATTAGE 1/16W
J 2
(-6500 2250);
DISPLAY 0.638298 (-6500 2250);
PAINT SKYBLUE (-6500 2250);
DISPLAY INVISIBLE (-6500 2250);
FORCEPROP 2 LAST CDS_LIB pure_quanta
J 0
(-6725 2125);
DISPLAY INVISIBLE (-6725 2125);
FORCEPROP 1 LAST PATH I314
J 0
(-6775 2275);
DISPLAY 0.978723 (-6775 2275);
PAINT WHITE (-6775 2275);
DISPLAY INVISIBLE (-6775 2275);
FORCEPROP 1 LAST PART_NUMBER CS01502FB03
J 0
(-6600 2100);
DISPLAY 0.489362 (-6600 2100);
PAINT SKYBLUE (-6600 2100);
DISPLAY INVISIBLE (-6600 2100);
FORCEADD OFFPAGE..1
(-7600 2125);
FORCEPROP 2 LAST $XR0 102 
J 0
(-7852 2125);
DISPLAY 0.638298 (-7852 2125);
PAINT MONO (-7852 2125);
FORCEPROP 2 LAST CDS_LIB mstr_standard
J 0
(-7600 2125);
DISPLAY INVISIBLE (-7600 2125);
FORCEPROP 1 LAST OFFPAGE TRUE
J 0
(-7275 2000);
DISPLAY 0.872340 (-7275 2000);
PAINT GREEN (-7275 2000);
DISPLAY INVISIBLE (-7275 2000);
FORCEPROP 1 LAST COMMENT_BODY TRUE
J 0
(-7475 2025);
DISPLAY 0.872340 (-7475 2025);
PAINT GREEN (-7475 2025);
DISPLAY INVISIBLE (-7475 2025);
FORCEPROP 2 LAST PATH I315
J 0
(-7850 2175);
DISPLAY 1.021277 (-7850 2175);
DISPLAY INVISIBLE (-7850 2175);
FORCEADD OFFPAGE..5
(-6650 2025);
FORCEPROP 2 LAST $XR0 102 
J 0
(-6905 2025);
DISPLAY 0.638298 (-6905 2025);
PAINT MONO (-6905 2025);
FORCEPROP 2 LAST CDS_LIB standard
J 0
(-6650 2025);
DISPLAY INVISIBLE (-6650 2025);
FORCEPROP 1 LAST OFFPAGE TRUE
J 0
(-6325 1900);
DISPLAY 0.872340 (-6325 1900);
PAINT GREEN (-6325 1900);
DISPLAY INVISIBLE (-6325 1900);
FORCEPROP 1 LAST COMMENT_BODY TRUE
J 0
(-6550 1950);
DISPLAY 0.872340 (-6550 1950);
PAINT GREEN (-6550 1950);
DISPLAY INVISIBLE (-6550 1950);
FORCEPROP 2 LAST PATH I316
J 0
(-6900 2075);
DISPLAY 1.021277 (-6900 2075);
DISPLAY INVISIBLE (-6900 2075);
FORCEADD CAD_NOTE..1
(-7800 2400);
FORCEPROP 0 LAST L1 R1962 PLACE CLOSE TO CPU < 25MM
J 0
(-7950 2275);
DISPLAY 0.617021 (-7950 2275);
PAINT WHITE (-7950 2275);
FORCEPROP 2 LAST CDS_LIB pure_quanta_power
J 0
(-7800 2400);
DISPLAY INVISIBLE (-7800 2400);
FORCEPROP 1 LAST COMMENT_BODY TRUE
J 0
(-7775 2500);
DISPLAY 0.574468 (-7775 2500);
PAINT WHITE (-7775 2500);
DISPLAY INVISIBLE (-7775 2500);
FORCEADD QUANTA_TITLE_BLOCK_C..1
(-100 100);
FORCEPROP 0 LAST CDS_CON_LAST_MODIFIED Thu Sep 14 16:11:56 2023
J 0
(-1985 115);
DISPLAY INVISIBLE (-1985 115);
FORCEPROP 1 LAST CUSTOM_TXT_CDS <CON_LAST_MODIFIED>
J 0
(-1985 115);
DISPLAY 0.978723 (-1985 115);
FORCEPROP 2 LAST CUSTOM_TXT_CDS <XR_PAGE_TITLE>
J 0
(-7990 5350);
DISPLAY 0.638298 (-7990 5350);
PAINT PINK (-7990 5350);
DISPLAY INVISIBLE (-7990 5350);
FORCEPROP 1 LAST CUSTOM_TXT_CDS <NAME_2>
J 0
(-3275 150);
FORCEPROP 1 LAST CUSTOM_TXT_CDS <NAME_1>
J 0
(-3275 275);
FORCEPROP 1 LAST CUSTOM_TXT_CDS <Q_NUMBER>
J 0
(-1503 203);
DISPLAY 1.212766 (-1503 203);
FORCEPROP 1 LAST CUSTOM_TXT_CDS <Q_PROJ>
J 0
(-2482 202);
DISPLAY 1.212766 (-2482 202);
FORCEPROP 1 LAST CUSTOM_TXT_CDS <Q_REV>
J 0
(-284 203);
DISPLAY 1.212766 (-284 203);
FORCEPROP 1 LAST CUSTOM_TXT_CDS <CON_PAGE_NUM> OF <CON_TOTAL_PAGES>
J 0
(-546 118);
DISPLAY 0.978723 (-546 118);
FORCEPROP 1 LAST Q_TITLE CPU1 DDR CHE
J 0
(-9400 150);
DISPLAY 2.446809 (-9400 150);
PAINT GREEN (-9400 150);
FORCEPROP 2 LAST PAGE_BORDER TRUE
J 0
(-7990 5350);
DISPLAY 0.638298 (-7990 5350);
PAINT PINK (-7990 5350);
DISPLAY INVISIBLE (-7990 5350);
FORCEPROP 2 LAST CDS_LIB pure_quanta
J 0
(-100 100);
DISPLAY INVISIBLE (-100 100);
FORCEPROP 1 LAST CDS_LMAN_SYM_OUTLINE -9475,6775,100,-125
J 0
(-100 100);
DISPLAY 0.468085 (-100 100);
PAINT GREEN (-100 100);
DISPLAY INVISIBLE (-100 100);
FORCEPROP 2 LAST CDS_XR_PAGE_TITLE CR-41 : @T6G_MB_LIB.T6G(SCH_1):PAGE41
J 0
(-7990 5350);
DISPLAY 0.638298 (-7990 5350);
PAINT PINK (-7990 5350);
DISPLAY INVISIBLE (-7990 5350);
FORCEPROP 1 LAST Q_DEPT BU9
J 1
(-3863 149);
DISPLAY 1.957447 (-3863 149);
PAINT GREEN (-3863 149);
DISPLAY INVISIBLE (-3863 149);
FORCEPROP 1 LAST COMMENT_BODY TRUE
J 0
(-88 87);
DISPLAY 0.978723 (-88 87);
PAINT GREEN (-88 87);
DISPLAY INVISIBLE (-88 87);
WIRE 17 -1 (-3375 6000)(-2750 6000);
FORCEPROP 2 LAST SIG_NAME M_E_CPU1_SA_DQ<31:0>
J 2
(-2810 6010);
DISPLAY 0.489362 (-2810 6010);
WIRE 17 -1 (-3375 6000)(-3375 5950);
WIRE 17 -1 (-3375 5950)(-3375 5900);
WIRE 17 -1 (-3375 5900)(-3375 5850);
WIRE 17 -1 (-3375 5850)(-3375 5800);
WIRE 17 -1 (-3375 5500)(-3375 5450);
WIRE 17 -1 (-3375 5550)(-3375 5500);
WIRE 17 -1 (-3375 5450)(-3375 5400);
WIRE 17 -1 (-3375 5400)(-3375 5350);
WIRE 17 -1 (-3375 5650)(-3375 5550);
WIRE 17 -1 (-3375 5700)(-3375 5650);
WIRE 17 -1 (-3375 5350)(-3375 5300);
WIRE 17 -1 (-3375 5300)(-3375 5250);
WIRE 17 -1 (-3375 5750)(-3375 5700);
WIRE 17 -1 (-3375 5800)(-3375 5750);
WIRE 17 -1 (-3375 5250)(-3375 5200);
WIRE 17 -1 (-3375 5100)(-3375 5200);
WIRE 17 -1 (-3375 5050)(-3375 5100);
WIRE 17 -1 (-3375 5000)(-3375 5050);
WIRE 17 -1 (-3375 4950)(-3375 5000);
WIRE 17 -1 (-3375 4950)(-3375 4900);
WIRE 17 -1 (-3375 4900)(-3375 4850);
WIRE 17 -1 (-3375 4850)(-3375 4800);
WIRE 17 -1 (-3375 4800)(-3375 4750);
WIRE 17 -1 (-3375 4750)(-3375 4650);
WIRE 17 -1 (-3375 4650)(-3375 4600);
WIRE 17 -1 (-3375 4600)(-3375 4550);
WIRE 17 -1 (-3375 4550)(-3375 4500);
WIRE 17 -1 (-3375 4450)(-3375 4500);
WIRE 17 -1 (-3375 4400)(-3375 4450);
WIRE 17 -1 (-3375 4200)(-2750 4200);
FORCEPROP 2 LAST SIG_NAME M_E_CPU1_SB_DQ<31:0>
J 2
(-2810 4210);
DISPLAY 0.489362 (-2810 4210);
WIRE 17 -1 (-3375 4350)(-3375 4400);
WIRE 17 -1 (-3375 4300)(-3375 4350);
WIRE 17 -1 (-3375 4200)(-3375 4150);
WIRE 17 -1 (-3375 3450)(-3375 3400);
WIRE 17 -1 (-3375 3500)(-3375 3450);
WIRE 17 -1 (-3375 3300)(-3375 3400);
WIRE 17 -1 (-3375 3250)(-3375 3300);
WIRE 17 -1 (-3375 3550)(-3375 3500);
WIRE 17 -1 (-3375 3600)(-3375 3550);
WIRE 17 -1 (-3375 3200)(-3375 3250);
WIRE 17 -1 (-3375 3150)(-3375 3200);
WIRE 17 -1 (-3375 3650)(-3375 3600);
WIRE 17 -1 (-3375 3700)(-3375 3650);
WIRE 17 -1 (-3375 3150)(-3375 3100);
WIRE 17 -1 (-3375 3100)(-3375 3050);
WIRE 17 -1 (-3375 3750)(-3375 3700);
WIRE 17 -1 (-3375 3850)(-3375 3750);
WIRE 17 -1 (-3375 3050)(-3375 3000);
WIRE 17 -1 (-3375 3000)(-3375 2950);
WIRE 17 -1 (-3375 3900)(-3375 3850);
WIRE 17 -1 (-3375 3950)(-3375 3900);
WIRE 17 -1 (-3375 2950)(-3375 2850);
WIRE 17 -1 (-3375 2850)(-3375 2800);
WIRE 17 -1 (-3375 4000)(-3375 3950);
WIRE 17 -1 (-3375 4050)(-3375 4000);
WIRE 17 -1 (-3375 2800)(-3375 2750);
WIRE 17 -1 (-3375 2750)(-3375 2700);
WIRE 17 -1 (-3375 4100)(-3375 4050);
WIRE 17 -1 (-3375 4150)(-3375 4100);
WIRE 17 -1 (-3375 2650)(-3375 2700);
WIRE 17 -1 (-3375 2600)(-3375 2650);
WIRE 17 -1 (-3375 2550)(-3375 2600);
WIRE 17 -1 (-3375 2500)(-3375 2550);
WIRE 17 -1 (-3375 2400)(-3375 2425);
WIRE 17 -1 (-3375 2400)(-3375 2350);
WIRE 17 -1 (-3375 2425)(-2875 2425);
FORCEPROP 2 LAST SIG_NAME M_E_CPU1_SA_CB<7:0>
J 2
(-2875 2435);
DISPLAY 0.489362 (-2875 2435);
WIRE 17 -1 (-3375 2300)(-3375 2350);
WIRE 17 -1 (-3375 2300)(-3375 2250);
WIRE 17 -1 (-3375 2200)(-3375 2250);
WIRE 17 -1 (-3375 2150)(-3375 2200);
WIRE 17 -1 (-3375 2100)(-3375 2150);
WIRE 17 -1 (-3375 2050)(-3375 2100);
WIRE 17 -1 (-3375 1650)(-3375 1700);
WIRE 17 -1 (-3375 1600)(-3375 1650);
WIRE 17 -1 (-3375 1700)(-3375 1750);
WIRE 17 -1 (-3375 1750)(-3375 1800);
WIRE 17 -1 (-3375 1850)(-3375 1800);
WIRE 17 -1 (-3375 1850)(-3375 1900);
WIRE 17 -1 (-3375 1950)(-3375 1900);
WIRE 17 -1 (-3375 1950)(-3375 1975);
WIRE 17 -1 (-3375 1975)(-2875 1975);
FORCEPROP 2 LAST SIG_NAME M_E_CPU1_SB_CB<7:0>
J 2
(-2875 1985);
DISPLAY 0.489362 (-2875 1985);
WIRE 17 -1 (-6100 5250)(-6100 5150);
WIRE 17 -1 (-6100 5250)(-6100 5350);
WIRE 17 -1 (-6100 5150)(-6100 5050);
WIRE 17 -1 (-6100 5350)(-6100 5450);
WIRE 17 -1 (-6100 5450)(-6100 5550);
WIRE 17 -1 (-6100 5650)(-6100 5550);
WIRE 17 -1 (-6100 5750)(-6100 5650);
WIRE 17 -1 (-6100 5850)(-6100 5750);
WIRE 17 -1 (-6100 5950)(-6100 5850);
FORCEPROP 2 LAST SIG_NAME M_E_CPU1_SA_DQS_DN<9:0>
J 2
(-6135 5960);
DISPLAY 0.489362 (-6135 5960);
WIRE 17 -1 (-5900 5700)(-5900 5600);
WIRE 17 -1 (-5900 5800)(-5900 5700);
WIRE 17 -1 (-5900 5500)(-5900 5600);
WIRE 17 -1 (-5900 5400)(-5900 5500);
WIRE 17 -1 (-5900 5900)(-5900 5800);
WIRE 17 -1 (-5900 6000)(-5900 5900);
WIRE 17 -1 (-5900 5300)(-5900 5400);
WIRE 17 -1 (-5900 5300)(-5900 5200);
WIRE 17 -1 (-5900 6000)(-6700 6000);
FORCEPROP 2 LAST SIG_NAME M_E_CPU1_SA_DQS_DP<9:0>
J 2
(-6135 6010);
DISPLAY 0.489362 (-6135 6010);
WIRE 17 -1 (-5900 5200)(-5900 5100);
WIRE 17 -1 (-6100 4800)(-6100 4700);
WIRE 17 -1 (-6100 4900)(-6100 4800);
FORCEPROP 2 LAST SIG_NAME M_E_CPU1_SB_DQS_DN<9:0>
J 2
(-6135 4910);
DISPLAY 0.489362 (-6135 4910);
WIRE 17 -1 (-6100 4700)(-6100 4600);
WIRE 17 -1 (-6100 4600)(-6100 4500);
WIRE 17 -1 (-6100 4400)(-6100 4500);
WIRE 17 -1 (-6100 4300)(-6100 4400);
WIRE 17 -1 (-5900 4950)(-5900 4850);
WIRE 17 -1 (-5900 4950)(-6700 4950);
FORCEPROP 2 LAST SIG_NAME M_E_CPU1_SB_DQS_DP<9:0>
J 2
(-6135 4960);
DISPLAY 0.489362 (-6135 4960);
WIRE 17 -1 (-6100 4200)(-6100 4300);
WIRE 17 -1 (-6100 4200)(-6100 4100);
WIRE 17 -1 (-6100 4100)(-6100 4000);
WIRE 17 -1 (-5900 4850)(-5900 4750);
WIRE 17 -1 (-5900 4750)(-5900 4650);
WIRE 17 -1 (-5900 4650)(-5900 4550);
WIRE 17 -1 (-5900 4450)(-5900 4550);
WIRE 17 -1 (-5900 4350)(-5900 4450);
WIRE 17 -1 (-5900 4250)(-5900 4350);
WIRE 17 -1 (-5900 4250)(-5900 4150);
WIRE 17 -1 (-5900 4150)(-5900 4050);
WIRE 17 -1 (-6100 3800)(-6100 3850);
WIRE 17 -1 (-6100 3750)(-6100 3800);
WIRE 17 -1 (-6100 3850)(-6600 3850);
FORCEPROP 2 LAST SIG_NAME M_E_CPU1_SA_CA<6:0>
J 0
(-6600 3860);
DISPLAY 0.489362 (-6600 3860);
WIRE 17 -1 (-6100 3400)(-6100 3450);
WIRE 17 -1 (-6100 3350)(-6100 3400);
WIRE 17 -1 (-6100 3450)(-6600 3450);
FORCEPROP 2 LAST SIG_NAME M_E_CPU1_SB_CA<6:0>
J 0
(-6600 3460);
DISPLAY 0.489362 (-6600 3460);
WIRE 17 -1 (-6100 3700)(-6100 3750);
WIRE 17 -1 (-6100 3300)(-6100 3350);
WIRE 17 -1 (-6100 3650)(-6100 3700);
WIRE 17 -1 (-6100 3600)(-6100 3650);
WIRE 17 -1 (-6100 3550)(-6100 3600);
WIRE 17 -1 (-6100 3250)(-6100 3300);
WIRE 17 -1 (-6100 3200)(-6100 3250);
WIRE 17 -1 (-6100 3150)(-6100 3200);
WIRE 17 -1 (-6100 5950)(-6700 5950);
WIRE 17 -1 (-6100 4900)(-6700 4900);
WIRE 16 -1 (-7550 2125)(-6825 2125);
FORCEPROP 2 LAST SIG_NAME M_E_CPU1_ALERT_N
J 0
(-7510 2135);
DISPLAY 0.489362 (-7510 2135);
WIRE 16 -1 (-6625 2125)(-5500 2125);
FORCEPROP 2 LAST SIG_NAME M_E_CPU1_ALERT_R_N
J 0
(-6335 2135);
DISPLAY 0.489362 (-6335 2135);
FORCEPROP 2 LASTPROP $XRERR UNIQUE?
J 0
(-6575 2135);
DISPLAY 0.638298 (-6575 2135);
PAINT MONO (-6575 2135);
DISPLAY INVISIBLE (-6575 2135);
WIRE 16 -1 (-6600 1175)(-5500 1175);
FORCEPROP 2 LAST SIG_NAME TP_M_E_CPU1_SA_TEST39E
J 0
(-6585 1185);
DISPLAY 0.489362 (-6585 1185);
FORCEPROP 2 LASTPROP $XRERR UNIQUE?
J 0
(-6840 1175);
DISPLAY 0.638298 (-6840 1175);
PAINT MONO (-6840 1175);
DISPLAY INVISIBLE (-6840 1175);
WIRE 16 -1 (-6600 2975)(-5500 2975);
FORCEPROP 2 LAST SIG_NAME M_E_CPU1_CLK_DP<0>
J 0
(-6600 2985);
DISPLAY 0.489362 (-6600 2985);
WIRE 16 -1 (-6600 2925)(-5500 2925);
FORCEPROP 2 LAST SIG_NAME M_E_CPU1_CLK_DN<0>
J 0
(-6600 2935);
DISPLAY 0.489362 (-6600 2935);
WIRE 16 -1 (-6600 2825)(-5500 2825);
FORCEPROP 2 LAST SIG_NAME M_E_CPU1_SA_CS_N<0>
J 0
(-6600 2835);
DISPLAY 0.489362 (-6600 2835);
WIRE 16 -1 (-6600 2675)(-5500 2675);
FORCEPROP 2 LAST SIG_NAME M_E_CPU1_SA_RSP<0>
J 0
(-6600 2685);
DISPLAY 0.489362 (-6600 2685);
WIRE 16 -1 (-6600 2775)(-5500 2775);
FORCEPROP 2 LAST SIG_NAME M_E_CPU1_SA_CS_N<1>
J 0
(-6600 2785);
DISPLAY 0.489362 (-6600 2785);
WIRE 16 -1 (-6600 2575)(-5500 2575);
FORCEPROP 2 LAST SIG_NAME M_E_CPU1_SA_PAR
J 0
(-6600 2585);
DISPLAY 0.489362 (-6600 2585);
WIRE 16 -1 (-6600 2425)(-5500 2425);
FORCEPROP 2 LAST SIG_NAME M_E_CPU1_SB_CS_N<1>
J 0
(-6600 2435);
DISPLAY 0.489362 (-6600 2435);
WIRE 16 -1 (-6600 2475)(-5500 2475);
FORCEPROP 2 LAST SIG_NAME M_E_CPU1_SB_CS_N<0>
J 0
(-6600 2485);
DISPLAY 0.489362 (-6600 2485);
WIRE 16 -1 (-6600 2325)(-5500 2325);
FORCEPROP 2 LAST SIG_NAME M_E_CPU1_SB_RSP<0>
J 0
(-6600 2335);
DISPLAY 0.489362 (-6600 2335);
WIRE 16 -1 (-6600 2225)(-5500 2225);
FORCEPROP 2 LAST SIG_NAME M_E_CPU1_SB_PAR
J 0
(-6600 2235);
DISPLAY 0.489362 (-6600 2235);
WIRE 16 -1 (-6600 2025)(-5500 2025);
FORCEPROP 2 LAST SIG_NAME M_E_CPU1_RESET_N
J 0
(-6600 2035);
DISPLAY 0.489362 (-6600 2035);
WIRE 16 -1 (-5800 4025)(-5500 4025);
WIRE 16 -1 (-6000 3125)(-5500 3125);
WIRE 16 -1 (-6000 3525)(-5500 3525);
WIRE 16 -1 (-6000 3175)(-5500 3175);
WIRE 16 -1 (-6000 3575)(-5500 3575);
WIRE 16 -1 (-6000 3225)(-5500 3225);
WIRE 16 -1 (-6000 3625)(-5500 3625);
WIRE 16 -1 (-6000 3275)(-5500 3275);
WIRE 16 -1 (-6000 3675)(-5500 3675);
WIRE 16 -1 (-6000 3325)(-5500 3325);
WIRE 16 -1 (-6000 3725)(-5500 3725);
WIRE 16 -1 (-6000 3375)(-5500 3375);
WIRE 16 -1 (-6000 3975)(-5500 3975);
WIRE 16 -1 (-6000 3775)(-5500 3775);
WIRE 16 -1 (-6000 3425)(-5500 3425);
WIRE 16 -1 (-6000 4075)(-5500 4075);
WIRE 16 -1 (-6000 3825)(-5500 3825);
WIRE 16 -1 (-6000 4775)(-5500 4775);
WIRE 16 -1 (-6000 4875)(-5500 4875);
WIRE 16 -1 (-5800 4125)(-5500 4125);
WIRE 16 -1 (-5800 4225)(-5500 4225);
WIRE 16 -1 (-5800 4325)(-5500 4325);
WIRE 16 -1 (-5800 4425)(-5500 4425);
WIRE 16 -1 (-5800 4525)(-5500 4525);
WIRE 16 -1 (-5800 5075)(-5500 5075);
WIRE 16 -1 (-5800 4625)(-5500 4625);
WIRE 16 -1 (-6000 4175)(-5500 4175);
WIRE 16 -1 (-5800 4725)(-5500 4725);
WIRE 16 -1 (-6000 4275)(-5500 4275);
WIRE 16 -1 (-5800 4825)(-5500 4825);
WIRE 16 -1 (-6000 4375)(-5500 4375);
WIRE 16 -1 (-5800 4925)(-5500 4925);
WIRE 16 -1 (-6000 4475)(-5500 4475);
WIRE 16 -1 (-6000 5025)(-5500 5025);
WIRE 16 -1 (-6000 4575)(-5500 4575);
WIRE 16 -1 (-6000 4675)(-5500 4675);
WIRE 16 -1 (-5800 5675)(-5500 5675);
WIRE 16 -1 (-6000 5225)(-5500 5225);
WIRE 16 -1 (-5800 5775)(-5500 5775);
WIRE 16 -1 (-6000 5325)(-5500 5325);
WIRE 16 -1 (-5800 5875)(-5500 5875);
WIRE 16 -1 (-6000 5425)(-5500 5425);
WIRE 16 -1 (-5800 5975)(-5500 5975);
WIRE 16 -1 (-6000 5525)(-5500 5525);
WIRE 16 -1 (-6000 5625)(-5500 5625);
WIRE 16 -1 (-6000 5725)(-5500 5725);
WIRE 16 -1 (-6000 5825)(-5500 5825);
WIRE 16 -1 (-6000 5925)(-5500 5925);
WIRE 16 -1 (-5800 5175)(-5500 5175);
WIRE 16 -1 (-5800 5275)(-5500 5275);
WIRE 16 -1 (-5800 5375)(-5500 5375);
WIRE 16 -1 (-5800 5475)(-5500 5475);
WIRE 16 -1 (-5800 5575)(-5500 5575);
WIRE 16 -1 (-6000 5125)(-5500 5125);
WIRE 16 -1 (-3900 1675)(-3475 1675);
WIRE 16 -1 (-3900 1725)(-3475 1725);
WIRE 16 -1 (-3900 1775)(-3475 1775);
WIRE 16 -1 (-3900 1825)(-3475 1825);
WIRE 16 -1 (-3900 2025)(-3475 2025);
WIRE 16 -1 (-3900 1875)(-3475 1875);
WIRE 16 -1 (-3900 1925)(-3475 1925);
WIRE 16 -1 (-3900 1575)(-3475 1575);
WIRE 16 -1 (-3900 1625)(-3475 1625);
WIRE 16 -1 (-3900 2775)(-3475 2775);
WIRE 16 -1 (-3900 2825)(-3475 2825);
WIRE 16 -1 (-3900 2925)(-3475 2925);
WIRE 16 -1 (-3900 2975)(-3475 2975);
WIRE 16 -1 (-3900 3025)(-3475 3025);
WIRE 16 -1 (-3900 2075)(-3475 2075);
WIRE 16 -1 (-3900 2475)(-3475 2475);
WIRE 16 -1 (-3900 2125)(-3475 2125);
WIRE 16 -1 (-3900 2525)(-3475 2525);
WIRE 16 -1 (-3900 2175)(-3475 2175);
WIRE 16 -1 (-3900 2225)(-3475 2225);
WIRE 16 -1 (-3900 2275)(-3475 2275);
WIRE 16 -1 (-3900 2325)(-3475 2325);
WIRE 16 -1 (-3900 2375)(-3475 2375);
WIRE 16 -1 (-3900 2575)(-3475 2575);
WIRE 16 -1 (-3900 2625)(-3475 2625);
WIRE 16 -1 (-3900 2675)(-3475 2675);
WIRE 16 -1 (-3900 2725)(-3475 2725);
WIRE 16 -1 (-3900 3425)(-3475 3425);
WIRE 16 -1 (-3900 3475)(-3475 3475);
WIRE 16 -1 (-3900 3525)(-3475 3525);
WIRE 16 -1 (-3900 3675)(-3475 3675);
WIRE 16 -1 (-3900 3575)(-3475 3575);
WIRE 16 -1 (-3900 3725)(-3475 3725);
WIRE 16 -1 (-3900 3625)(-3475 3625);
WIRE 16 -1 (-3900 3825)(-3475 3825);
WIRE 16 -1 (-3900 3075)(-3475 3075);
WIRE 16 -1 (-3900 3875)(-3475 3875);
WIRE 16 -1 (-3900 3925)(-3475 3925);
WIRE 16 -1 (-3900 3975)(-3475 3975);
WIRE 16 -1 (-3900 4025)(-3475 4025);
WIRE 16 -1 (-3900 4075)(-3475 4075);
WIRE 16 -1 (-3900 3125)(-3475 3125);
WIRE 16 -1 (-3900 3175)(-3475 3175);
WIRE 16 -1 (-3900 3225)(-3475 3225);
WIRE 16 -1 (-3900 3275)(-3475 3275);
WIRE 16 -1 (-3900 3375)(-3475 3375);
WIRE 16 -1 (-3900 4925)(-3475 4925);
WIRE 16 -1 (-3900 4975)(-3475 4975);
WIRE 16 -1 (-3900 4375)(-3475 4375);
WIRE 16 -1 (-3900 5025)(-3475 5025);
WIRE 16 -1 (-3900 4425)(-3475 4425);
WIRE 16 -1 (-3900 5075)(-3475 5075);
WIRE 16 -1 (-3900 4475)(-3475 4475);
WIRE 16 -1 (-3900 4525)(-3475 4525);
WIRE 16 -1 (-3900 4575)(-3475 4575);
WIRE 16 -1 (-3900 4625)(-3475 4625);
WIRE 16 -1 (-3900 4725)(-3475 4725);
WIRE 16 -1 (-3900 4775)(-3475 4775);
WIRE 16 -1 (-3900 4825)(-3475 4825);
WIRE 16 -1 (-3900 4875)(-3475 4875);
WIRE 16 -1 (-3900 4275)(-3475 4275);
WIRE 16 -1 (-3900 4125)(-3475 4125);
WIRE 16 -1 (-3900 4325)(-3475 4325);
WIRE 16 -1 (-3900 4175)(-3475 4175);
WIRE 16 -1 (-3900 5475)(-3475 5475);
WIRE 16 -1 (-3900 5525)(-3475 5525);
WIRE 16 -1 (-3900 5175)(-3475 5175);
WIRE 16 -1 (-3900 5625)(-3475 5625);
WIRE 16 -1 (-3900 5225)(-3475 5225);
WIRE 16 -1 (-3900 5675)(-3475 5675);
WIRE 16 -1 (-3900 5275)(-3475 5275);
WIRE 16 -1 (-3900 5725)(-3475 5725);
WIRE 16 -1 (-3900 5325)(-3475 5325);
WIRE 16 -1 (-3900 5775)(-3475 5775);
WIRE 16 -1 (-3900 5375)(-3475 5375);
WIRE 16 -1 (-3900 5825)(-3475 5825);
WIRE 16 -1 (-3900 5425)(-3475 5425);
WIRE 16 -1 (-3900 5875)(-3475 5875);
WIRE 16 -1 (-3900 5925)(-3475 5925);
WIRE 16 -1 (-3900 5975)(-3475 5975);
QUIT
